G04 ================== begin FILE IDENTIFICATION RECORD ==================*
G04 Layout Name:  D:/<user>/Wistron_project/16318-2/gbr/16318-2.brd*
G04 Film Name:    L4VCC*
G04 File Format:  Gerber RS274X*
G04 File Origin:  Cadence Allegro 16.5-S056*
G04 Origin Date:  Mon Aug 07 11:09:43 2017*
G04 *
G04 Layer:  VIA CLASS/L4VCC*
G04 Layer:  PIN/L4VCC*
G04 Layer:  PACKAGE GEOMETRY/PWRVCC*
G04 Layer:  ETCH/L4VCC*
G04 Layer:  DRAWING FORMAT/LAYER_PCB_STORY*
G04 Layer:  DRAWING FORMAT/LAYER_L4VCC*
G04 *
G04 Offset:    (0.00 0.00)*
G04 Mirror:    No*
G04 Mode:      Negative*
G04 Rotation:  0*
G04 FullContactRelief:  No*
G04 UndefLineWidth:     6.00*
G04 ================== end FILE IDENTIFICATION RECORD ====================*
%FSLAX35Y35*MOIN*%
%IR0*IPPOS*OFA0.00000B0.00000*MIA0B0*SFA1.00000B1.00000*%
%ADD27O,.072X.123*%
%ADD14C,.03*%
%ADD21C,.032*%
%ADD37C,.051*%
%ADD26C,.06*%
%ADD32C,.043*%
%ADD30C,.062*%
%ADD35C,.063*%
%ADD11C,.036*%
%ADD23C,.028*%
%ADD31C,.056*%
%ADD29C,.076*%
%ADD12C,.068*%
%AMMACRO19*
4,1,15,.00398,.00044,
.003999,.000208,
.004004,-.000025,
.003996,-.000258,
.00398,-.00044,
.00483,-.00129,
.004897,-.001007,
.004947,-.000721,
.004981,-.000432,
.004997,-.000141,
.004997,.000149,
.00498,.00044,
.004946,.000729,
.004895,.001015,
.00483,.00129,
.00398,.00044,
90.*
4,1,15,.00044,-.00398,
.000208,-.003999,
-.000025,-.004004,
-.000258,-.003996,
-.00044,-.00398,
-.00129,-.00483,
-.001007,-.004897,
-.000721,-.004947,
-.000432,-.004981,
-.000141,-.004997,
.000149,-.004997,
.00044,-.00498,
.000729,-.004946,
.001015,-.004895,
.00129,-.00483,
.00044,-.00398,
90.*
4,1,15,-.00398,-.00044,
-.003999,-.000208,
-.004004,.000025,
-.003996,.000258,
-.00398,.00044,
-.00483,.00129,
-.004897,.001007,
-.004947,.000721,
-.004981,.000432,
-.004997,.000141,
-.004997,-.000149,
-.00498,-.00044,
-.004946,-.000729,
-.004895,-.001015,
-.00483,-.00129,
-.00398,-.00044,
90.*
4,1,15,-.00044,.00398,
-.000208,.003999,
.000025,.004004,
.000258,.003996,
.00044,.00398,
.00129,.00483,
.001007,.004897,
.000721,.004947,
.000432,.004981,
.000141,.004997,
-.000149,.004997,
-.00044,.00498,
-.000729,.004946,
-.001015,.004895,
-.00129,.00483,
-.00044,.00398,
90.*
%
%ADD19MACRO19*%
%AMMACRO24*
4,1,15,-.00398,.00044,
-.003999,.000208,
-.004004,-.000025,
-.003996,-.000258,
-.00398,-.00044,
-.00483,-.00129,
-.004897,-.001007,
-.004947,-.000721,
-.004981,-.000432,
-.004997,-.000141,
-.004997,.000149,
-.00498,.00044,
-.004946,.000729,
-.004895,.001015,
-.00483,.00129,
-.00398,.00044,
90.*
4,1,15,-.00044,-.00398,
-.000208,-.003999,
.000025,-.004004,
.000258,-.003996,
.00044,-.00398,
.00129,-.00483,
.001007,-.004897,
.000721,-.004947,
.000432,-.004981,
.000141,-.004997,
-.000149,-.004997,
-.00044,-.00498,
-.000729,-.004946,
-.001015,-.004895,
-.00129,-.00483,
-.00044,-.00398,
90.*
4,1,15,.00398,-.00044,
.003999,-.000208,
.004004,.000025,
.003996,.000258,
.00398,.00044,
.00483,.00129,
.004897,.001007,
.004947,.000721,
.004981,.000432,
.004997,.000141,
.004997,-.000149,
.00498,-.00044,
.004946,-.000729,
.004895,-.001015,
.00483,-.00129,
.00398,-.00044,
90.*
4,1,15,.00044,.00398,
.000208,.003999,
-.000025,.004004,
-.000258,.003996,
-.00044,.00398,
-.00129,.00483,
-.001007,.004897,
-.000721,.004947,
-.000432,.004981,
-.000141,.004997,
.000149,.004997,
.00044,.00498,
.000729,.004946,
.001015,.004895,
.00129,.00483,
.00044,.00398,
90.*
%
%ADD24MACRO24*%
%AMMACRO10*
4,1,15,.00398,.00044,
.003999,.000208,
.004004,-.000025,
.003996,-.000258,
.00398,-.00044,
.00483,-.00129,
.004897,-.001007,
.004947,-.000721,
.004981,-.000432,
.004997,-.000141,
.004997,.000149,
.00498,.00044,
.004946,.000729,
.004895,.001015,
.00483,.00129,
.00398,.00044,
0.0*
4,1,15,.00044,-.00398,
.000208,-.003999,
-.000025,-.004004,
-.000258,-.003996,
-.00044,-.00398,
-.00129,-.00483,
-.001007,-.004897,
-.000721,-.004947,
-.000432,-.004981,
-.000141,-.004997,
.000149,-.004997,
.00044,-.00498,
.000729,-.004946,
.001015,-.004895,
.00129,-.00483,
.00044,-.00398,
0.0*
4,1,15,-.00398,-.00044,
-.003999,-.000208,
-.004004,.000025,
-.003996,.000258,
-.00398,.00044,
-.00483,.00129,
-.004897,.001007,
-.004947,.000721,
-.004981,.000432,
-.004997,.000141,
-.004997,-.000149,
-.00498,-.00044,
-.004946,-.000729,
-.004895,-.001015,
-.00483,-.00129,
-.00398,-.00044,
0.0*
4,1,15,-.00044,.00398,
-.000208,.003999,
.000025,.004004,
.000258,.003996,
.00044,.00398,
.00129,.00483,
.001007,.004897,
.000721,.004947,
.000432,.004981,
.000141,.004997,
-.000149,.004997,
-.00044,.00498,
-.000729,.004946,
-.001015,.004895,
-.00129,.00483,
-.00044,.00398,
0.0*
%
%ADD10MACRO10*%
%ADD34C,.122*%
%ADD13C,.114*%
%ADD33C,.125*%
%ADD36C,.127*%
%ADD25C,.208*%
%ADD16O,.296X.162*%
%ADD38C,.147*%
%ADD28O,.072X.096*%
%ADD22C,.158*%
%ADD15C,.178*%
%ADD20C,.198*%
%AMMACRO18*
4,1,15,.00398,.00044,
.003999,.000208,
.004004,-.000025,
.003996,-.000258,
.00398,-.00044,
.00483,-.00129,
.004897,-.001007,
.004947,-.000721,
.004981,-.000432,
.004997,-.000141,
.004997,.000149,
.00498,.00044,
.004946,.000729,
.004895,.001015,
.00483,.00129,
.00398,.00044,
180.*
4,1,15,.00044,-.00398,
.000208,-.003999,
-.000025,-.004004,
-.000258,-.003996,
-.00044,-.00398,
-.00129,-.00483,
-.001007,-.004897,
-.000721,-.004947,
-.000432,-.004981,
-.000141,-.004997,
.000149,-.004997,
.00044,-.00498,
.000729,-.004946,
.001015,-.004895,
.00129,-.00483,
.00044,-.00398,
180.*
4,1,15,-.00398,-.00044,
-.003999,-.000208,
-.004004,.000025,
-.003996,.000258,
-.00398,.00044,
-.00483,.00129,
-.004897,.001007,
-.004947,.000721,
-.004981,.000432,
-.004997,.000141,
-.004997,-.000149,
-.00498,-.00044,
-.004946,-.000729,
-.004895,-.001015,
-.00483,-.00129,
-.00398,-.00044,
180.*
4,1,15,-.00044,.00398,
-.000208,.003999,
.000025,.004004,
.000258,.003996,
.00044,.00398,
.00129,.00483,
.001007,.004897,
.000721,.004947,
.000432,.004981,
.000141,.004997,
-.000149,.004997,
-.00044,.00498,
-.000729,.004946,
-.001015,.004895,
-.00129,.00483,
-.00044,.00398,
180.*
%
%ADD18MACRO18*%
%AMMACRO17*
4,1,15,.00398,.00044,
.003999,.000208,
.004004,-.000025,
.003996,-.000258,
.00398,-.00044,
.00483,-.00129,
.004897,-.001007,
.004947,-.000721,
.004981,-.000432,
.004997,-.000141,
.004997,.000149,
.00498,.00044,
.004946,.000729,
.004895,.001015,
.00483,.00129,
.00398,.00044,
270.*
4,1,15,.00044,-.00398,
.000208,-.003999,
-.000025,-.004004,
-.000258,-.003996,
-.00044,-.00398,
-.00129,-.00483,
-.001007,-.004897,
-.000721,-.004947,
-.000432,-.004981,
-.000141,-.004997,
.000149,-.004997,
.00044,-.00498,
.000729,-.004946,
.001015,-.004895,
.00129,-.00483,
.00044,-.00398,
270.*
4,1,15,-.00398,-.00044,
-.003999,-.000208,
-.004004,.000025,
-.003996,.000258,
-.00398,.00044,
-.00483,.00129,
-.004897,.001007,
-.004947,.000721,
-.004981,.000432,
-.004997,.000141,
-.004997,-.000149,
-.00498,-.00044,
-.004946,-.000729,
-.004895,-.001015,
-.00483,-.00129,
-.00398,-.00044,
270.*
4,1,15,-.00044,.00398,
-.000208,.003999,
.000025,.004004,
.000258,.003996,
.00044,.00398,
.00129,.00483,
.001007,.004897,
.000721,.004947,
.000432,.004981,
.000141,.004997,
-.000149,.004997,
-.00044,.00498,
-.000729,.004946,
-.001015,.004895,
-.00129,.00483,
-.00044,.00398,
270.*
%
%ADD17MACRO17*%
%ADD39C,.02*%
%ADD40C,.006*%
%ADD47C,.07204*%
%ADD52C,.05604*%
%ADD48C,.05804*%
%ADD41C,.08982*%
%ADD43C,.11004*%
%ADD53C,.12104*%
%ADD54C,.11804*%
%ADD45C,.15404*%
%ADD46O,.29202X.15802*%
%ADD55C,.23626*%
%ADD42O,.29204X.15804*%
%ADD50C,.2369*%
%ADD44C,.37406*%
%ADD51C,.2964*%
%ADD49C,.37566*%
G75*
%LPD*%
G75*
G36*
G01X-6000Y-6000D02*
X931197D01*
Y769780D01*
X-6000D01*
Y-6000D01*
G37*
%LPC*%
G75*
G36*
G01X115197Y426762D02*
Y5000D01*
X5000D01*
Y425839D01*
X5923Y426762D01*
X6384D01*
X6444Y426685D01*
G03X10614Y426762I2056J1594D01*
G01X115197D01*
G37*
G36*
G01X740911Y42750D02*
X762111Y63950D01*
X778011D01*
X831250Y117189D01*
Y218611D01*
X825250Y224611D01*
Y264686D01*
X826338Y265758D01*
X831250Y270669D01*
Y405311D01*
X820750Y415811D01*
Y434898D01*
G03Y438102I-2050J1602D01*
G01Y444811D01*
X816311Y449250D01*
X756189D01*
X745750Y438811D01*
Y401311D01*
X744196Y399757D01*
X712804D01*
X696250Y416311D01*
Y446811D01*
X693111Y449950D01*
X654681D01*
X652750Y451881D01*
Y488985D01*
X647550Y494185D01*
Y520783D01*
G03Y523017I-2350J1117D01*
G01Y576978D01*
X691761Y621189D01*
X919350D01*
X920197Y620342D01*
Y5000D01*
X292520D01*
Y429331D01*
G03X283583Y438268I-8937J0D01*
G01X124134D01*
G03X115197Y429331I0J-8937D01*
G01Y428262D01*
X5699D01*
X5000Y428961D01*
Y718039D01*
X5686Y718725D01*
X52762D01*
X57189Y723152D01*
X57221Y723167D01*
G03X64504Y729250I-8008J16990D01*
G01X95189D01*
X97250Y727189D01*
Y701311D01*
X92689Y696750D01*
X72689D01*
X44750Y668811D01*
Y470189D01*
X62689Y452250D01*
X112396D01*
G03X115952Y451633I1994J935D01*
G02X116524Y451629I284J-281D01*
G03X119680Y451617I1584J1530D01*
G02X120252I286J-280D01*
G03X122980Y451280I1575J1539D01*
G02X123522Y451162I210J-340D01*
G03X127037Y450966I1831J1223D01*
G02X127593Y451021I306J-257D01*
G03X131077Y452108I1375J1720D01*
G01X131120Y452250D01*
X253442D01*
G03X256358I1458J1650D01*
G01X257542D01*
G03X260458I1458J1650D01*
G01X279387D01*
G03X283013I1813J1250D01*
G01X314689D01*
X347850Y419089D01*
Y399995D01*
X343661Y395806D01*
G03X342808Y394953I1071J-1924D01*
G01X330150Y382295D01*
Y205941D01*
X332089Y204002D01*
X333434D01*
G03X336830I1698J1972D01*
G01X365437D01*
X366750Y202689D01*
Y190189D01*
X372689Y184250D01*
X384238D01*
X390250Y178238D01*
Y176575D01*
G03Y174193I1852J-1191D01*
G01Y89313D01*
X390126Y89262D01*
G03Y85190I838J-2036D01*
G01X390250Y85139D01*
Y80289D01*
X391510Y79029D01*
X391412Y78891D01*
G03X394483Y75820I1794J-1277D01*
G01X394621Y75918D01*
X413335Y57204D01*
G02X412894Y56554I-283J-283D01*
G03X422696Y46752I-7382J-17184D01*
G02X423346Y47193I367J158D01*
G01X430789Y39750D01*
X464231D01*
X467081Y42600D01*
X469319D01*
X472169Y39750D01*
X485091D01*
G03X487137I1023J1950D01*
G01X505567D01*
X510729Y44912D01*
X518744D01*
G02X519129Y44404I0J-400D01*
G03X523145Y41582I2505J-703D01*
G01X523282Y41681D01*
X528713Y36250D01*
X556990D01*
X557007Y36068D01*
G03X561393I2193J197D01*
G01X561410Y36250D01*
X586811D01*
X593311Y42750D01*
X740911D01*
G37*
G36*
G01X43347Y758000D02*
G03X52560Y721675I5866J-17843D01*
G02X52914Y720999I71J-394D01*
G01X52140Y720225D01*
X10227D01*
G03X6827Y720272I-1727J-1946D01*
G01X6771Y720225D01*
X5936D01*
X5000Y721161D01*
Y723229D01*
X22776Y758780D01*
X43222D01*
G02X43347Y758000I0J-400D01*
G37*
G36*
G01X381250Y570311D02*
Y564935D01*
G03Y562415I1806J-1260D01*
G01Y534189D01*
X383750Y531689D01*
Y530301D01*
G03X383721Y527959I1850J-1194D01*
G01X383750Y527911D01*
Y527407D01*
G03X383353Y523883I1099J-1908D01*
G02Y523297I-272J-293D01*
G03X383750Y519773I1496J-1616D01*
G01Y451224D01*
X383620Y451175D01*
G03Y447053I775J-2061D01*
G01X383750Y447004D01*
Y187511D01*
X381989Y185750D01*
X373311D01*
X368250Y190811D01*
Y203311D01*
X366059Y205502D01*
X360702D01*
X360667Y205515D01*
G03X359097I-785J-2057D01*
G01X359062Y205502D01*
X332711D01*
X331650Y206563D01*
Y381673D01*
X349350Y399373D01*
Y419711D01*
X315962Y453099D01*
G02X316218Y453781I283J283D01*
G03X333662Y472441I-1258J18660D01*
G03X296258I-18702J0D01*
G03X309569Y454533I18702J0D01*
G02X309454Y453750I-115J-383D01*
G01X283394D01*
X283363Y453913D01*
G03X279037I-2163J-413D01*
G01X279006Y453750D01*
X130925D01*
G03X127284Y454160I-1957J-1009D01*
G02X126728Y454105I-306J257D01*
G03X124199Y454261I-1375J-1720D01*
G02X123657Y454379I-210J340D01*
G03X120254Y454698I-1831J-1223D01*
G02X119682I-286J280D01*
G03X116546Y454711I-1574J-1539D01*
G02X115974Y454715I-284J281D01*
G03X112303Y453886I-1584J-1530D01*
G01X112257Y453750D01*
X76374D01*
G02X76259Y454533I0J400D01*
G03X54189Y463975I-5393J17908D01*
G02X53550Y463511I-357J-181D01*
G01X46250Y470811D01*
Y497089D01*
X47411Y498250D01*
X129481D01*
X139720Y508489D01*
Y515949D01*
X145626Y521855D01*
X145693Y521864D01*
G03X146710Y525816I-293J2182D01*
G01Y539611D01*
X146580Y539741D01*
X159599Y552760D01*
X172369D01*
X174600Y554991D01*
Y568511D01*
X177340Y571251D01*
Y580659D01*
X171320Y586679D01*
Y590779D01*
X169979Y592120D01*
X158669D01*
X156700Y594089D01*
Y596639D01*
X156850Y596789D01*
Y597411D01*
X144111Y610150D01*
X112989D01*
X111689Y608850D01*
X102411D01*
X101200Y610061D01*
Y628511D01*
X96011Y633700D01*
X46681D01*
X46250Y634131D01*
Y668189D01*
X51911Y673850D01*
X53589D01*
X54189Y673250D01*
X72919D01*
G03X77681I2381J1050D01*
G01X79470D01*
G03X83130I1830J1850D01*
G01X90311D01*
X98302Y681241D01*
X98431Y681176D01*
G03X102048Y682618I1169J2324D01*
G01X102096Y682750D01*
X124811D01*
X149151Y707090D01*
X153081D01*
X156450Y710459D01*
Y714389D01*
X182811Y740750D01*
X291089D01*
X300589Y731250D01*
X314189D01*
X317750Y727689D01*
Y712127D01*
X317748Y712112D01*
G03Y711328I2572J-392D01*
G01X317750Y711313D01*
Y702699D01*
X328370Y692079D01*
Y674931D01*
X318689Y665250D01*
X307189D01*
X305689Y663750D01*
X299689D01*
X297750Y661811D01*
Y649689D01*
X301189Y646250D01*
X348760D01*
G03X352240I1740J1350D01*
G01X366469D01*
X377900Y634819D01*
Y618659D01*
X379843Y616716D01*
X379819Y616608D01*
G03X383508Y614550I2148J-485D01*
G01X385619D01*
X386750Y613419D01*
Y575811D01*
X381250Y570311D01*
G37*
G36*
G01X145210Y539611D02*
Y526246D01*
X145042Y526219D01*
G03X143849Y522483I358J-2173D01*
G01X143990Y522341D01*
X138220Y516571D01*
Y509111D01*
X128859Y499750D01*
X47411D01*
X46250Y500911D01*
Y631619D01*
X46831Y632200D01*
X95389D01*
X99700Y627889D01*
Y609439D01*
X101789Y607350D01*
X112311D01*
X113611Y608650D01*
X143489D01*
X155500Y596639D01*
Y593591D01*
X158171Y590920D01*
X169481D01*
X170120Y590281D01*
Y586181D01*
X176140Y580161D01*
Y571749D01*
X173400Y569009D01*
Y558892D01*
X173390Y558862D01*
G03Y557674I1807J-594D01*
G01X173400Y557644D01*
Y555489D01*
X171871Y553960D01*
X159101D01*
X145360Y540219D01*
Y539761D01*
X145210Y539611D01*
G37*
G36*
G01X411750Y100689D02*
X446389Y66050D01*
X476001D01*
X476004Y66047D01*
X476626D01*
X476629Y66050D01*
X508589D01*
X512489Y62150D01*
X517718D01*
G03X521349Y61175I2282J1250D01*
G01X521483Y61256D01*
X525639Y57100D01*
X555161D01*
X566469Y68408D01*
X566609Y68293D01*
G03X569707Y71391I1391J1707D01*
G01X569592Y71531D01*
X570750Y72689D01*
Y118085D01*
X570779Y118114D01*
Y118736D01*
X570750Y118765D01*
Y183749D01*
G03X573110Y188975I-4609J5227D01*
G01Y491449D01*
X573777Y492116D01*
G02X574399Y492044I282J-283D01*
G03X579085Y492612I2211J1372D01*
G01X579130Y492750D01*
X646737D01*
X646800Y492813D01*
X651250Y488363D01*
Y355311D01*
X592250Y296311D01*
Y43811D01*
X586189Y37750D01*
X560826D01*
G03X557574I-1626J-1485D01*
G01X529335D01*
X524129Y42956D01*
X524157Y43066D01*
G03X520999Y46224I-2523J635D01*
G01X520889Y46196D01*
X520673Y46412D01*
X510107D01*
X504945Y41250D01*
X472791D01*
X469941Y44100D01*
X466459D01*
X463609Y41250D01*
X431411D01*
X395384Y77277D01*
X395395Y77372D01*
G03X392964Y79803I-2189J242D01*
G01X392869Y79792D01*
X392633Y80028D01*
X392622Y80089D01*
G03X391750Y81475I-2166J-396D01*
G01Y85169D01*
G03Y89283I-786J2057D01*
G01Y178860D01*
X385250Y185360D01*
Y329084D01*
X385260Y329114D01*
G03Y330500I-2090J693D01*
G01X385250Y330530D01*
Y342306D01*
G03Y344452I-1923J1073D01*
G01Y346120D01*
G03Y348108I-1965J994D01*
G01Y447085D01*
G03Y451143I-855J2029D01*
G01Y519510D01*
X385400Y519549D01*
G03X386345Y523297I-551J2132D01*
G02Y523883I272J293D01*
G03X385400Y527631I-1496J1616D01*
G01X385250Y527670D01*
Y532311D01*
X382750Y534811D01*
Y569689D01*
X388250Y575189D01*
Y580615D01*
G03Y582679I-1945J1032D01*
G01Y614041D01*
X386241Y616050D01*
X384176D01*
X384166Y616239D01*
G03X380734Y617947I-2199J-116D01*
G01X379400Y619281D01*
Y635441D01*
X367091Y647750D01*
X352704D01*
X352678Y647921D01*
G03X348322I-2178J-321D01*
G01X348296Y647750D01*
X301811D01*
X299250Y650311D01*
Y661189D01*
X300311Y662250D01*
X306311D01*
X307811Y663750D01*
X319311D01*
X329870Y674309D01*
Y692701D01*
X319250Y703321D01*
Y728311D01*
X314811Y732750D01*
X301211D01*
X291711Y742250D01*
X182189D01*
X154950Y715011D01*
Y711081D01*
X152459Y708590D01*
X148529D01*
X133451Y693512D01*
X133406Y693498D01*
G03X131752Y691844I817J-2471D01*
G01X131738Y691799D01*
X124189Y684250D01*
X102096D01*
X102048Y684382D01*
G03X97274Y682335I-2448J-882D01*
G01X89689Y674750D01*
X77868D01*
X77831Y674904D01*
G03X72769I-2531J-604D01*
G01X72732Y674750D01*
X54811D01*
X54650Y674911D01*
Y676589D01*
X73311Y695250D01*
X74906D01*
G03X77294I1194J1850D01*
G01X93311D01*
X98750Y700689D01*
Y727811D01*
X96250Y730311D01*
Y741289D01*
X97277Y742316D01*
X97322Y742331D01*
G03X98969Y743978I-822J2469D01*
G01X98984Y744023D01*
X107904Y752943D01*
X108029Y752890D01*
G03X111391Y756430I1028J2390D01*
G01X113741Y758780D01*
X334859D01*
X335550Y758089D01*
Y737689D01*
X353489Y719750D01*
X380789D01*
X396907Y703632D01*
X396899Y703539D01*
G03X400939Y702150I2194J-189D01*
G01X402289D01*
X403268Y701171D01*
Y188976D01*
G03X410050Y182010I6969J0D01*
G01Y180389D01*
X411750Y178689D01*
Y100689D01*
G37*
G36*
G01X110370Y757531D02*
X110241Y757597D01*
G03X106809Y753970I-1184J-2317D01*
G01X99655Y746816D01*
G03X99290Y746452I1646J-2015D01*
G01X99284Y746445D01*
X94750Y741911D01*
Y730750D01*
X66149D01*
G02X65796Y731338I0J400D01*
G03X55079Y758000I-16583J8819D01*
G02X55204Y758780I125J380D01*
G01X110653D01*
G02X110936Y758097I0J-400D01*
G01X110370Y757531D01*
G37*
G36*
G01X354111Y721250D02*
X337050Y738311D01*
Y757689D01*
X338141Y758780D01*
X358444D01*
G02X358564Y757998I0J-400D01*
G03X359540Y722037I5609J-17842D01*
G02X359441Y721250I-100J-387D01*
G01X354111D01*
G37*
G36*
G01X401280Y703650D02*
X401247Y703808D01*
G03X397649Y705012I-2154J-458D01*
G01X381411Y721250D01*
X368905D01*
G02X368806Y722037I1J400D01*
G03X369782Y757998I-4633J18119D01*
G02X369902Y758780I120J382D01*
G01X385492D01*
X403268Y723229D01*
Y704629D01*
X402289Y703650D01*
X401280D01*
G37*
G36*
G01X447011Y67550D02*
X413250Y101311D01*
Y179311D01*
X411550Y181011D01*
Y182131D01*
X411708Y182165D01*
G03X415090Y183976I-1471J6811D01*
G01X476838D01*
Y71434D01*
X476701Y71388D01*
G03X475518Y68157I699J-2088D01*
G02X475176Y67550I-342J-207D01*
G01X447011D01*
G37*
G36*
G01X565801Y69862D02*
X554539Y58600D01*
X526261D01*
X522421Y62440D01*
X522462Y62558D01*
G03X517432Y63818I-2462J842D01*
G01X517404Y63650D01*
X513111D01*
X509211Y67550D01*
X479209D01*
X478992Y67767D01*
X479106Y67908D01*
G03X478338Y71292I-1706J1392D01*
G01Y183976D01*
X530973D01*
Y120048D01*
X534353Y116668D01*
X568737D01*
X569250Y116155D01*
Y73311D01*
X568138Y72199D01*
X568053Y72201D01*
G03X565799Y69947I-53J-2201D01*
G01X565801Y69862D01*
G37*
G36*
G01X534975Y118168D02*
X532473Y120670D01*
Y183976D01*
X561288D01*
G03X568703Y182496I4853J5000D01*
G02X569250Y182124I147J-372D01*
G01Y118707D01*
X568711Y118168D01*
X534975D01*
G37*
G36*
G01X829750Y117811D02*
X777389Y65450D01*
X761489D01*
X740289Y44250D01*
X595311D01*
X593750Y45811D01*
Y155289D01*
X595711Y157250D01*
X828039D01*
X829750Y155539D01*
Y117811D01*
G37*
G36*
G01X757250Y367461D02*
X718645Y328856D01*
X718579Y328847D01*
G03X716363Y326631I361J-2577D01*
G01X716354Y326565D01*
X715250Y325461D01*
Y320589D01*
X717289Y318550D01*
X731989D01*
X751150Y299389D01*
Y288211D01*
X749689Y286750D01*
X730989D01*
X728150Y283911D01*
Y226089D01*
X730689Y223550D01*
X745630D01*
G03X747284I827J1254D01*
G01X748779D01*
G03X750433I827J1254D01*
G01X751311D01*
X753311Y225550D01*
X772889D01*
X773330Y225109D01*
X773316Y225011D01*
G03X775011Y223316I1488J-207D01*
G01X775109Y223330D01*
X775189Y223250D01*
X824489D01*
X829750Y217989D01*
Y200460D01*
G03Y197798I1754J-1331D01*
G01Y160761D01*
X827739Y158750D01*
X595711D01*
X593811Y160650D01*
X593750D01*
Y295689D01*
X652750Y354689D01*
Y446679D01*
X654521Y448450D01*
X692489D01*
X694750Y446189D01*
Y415689D01*
X712182Y398257D01*
X744182D01*
X744189Y398250D01*
X744811D01*
X744818Y398257D01*
X748182D01*
X748189Y398250D01*
X748811D01*
X748818Y398257D01*
X754189D01*
X757250Y395196D01*
Y367461D01*
G37*
G36*
G01X606596Y757998D02*
G03X617814I5609J-17841D01*
G02X617933Y758780I120J382D01*
G01X870256D01*
G02X870375Y757998I-1J-400D01*
G03X881593I5609J-17841D01*
G02X881712Y758780I120J382D01*
G01X902421D01*
X920197Y723229D01*
Y623458D01*
X919428Y622689D01*
X691139D01*
X646050Y577600D01*
Y496011D01*
X644289Y494250D01*
X579078D01*
X579028Y494376D01*
G03X574770Y495256I-2418J-960D01*
G02X574205I-282J283D01*
G01X573110Y496351D01*
Y723229D01*
X590886Y758780D01*
X606477D01*
G02X606596Y757998I-1J-400D01*
G37*
G36*
G01X776316Y224750D02*
X776300Y224933D01*
G03X774438Y226261I-1496J-129D01*
G01X774328Y226233D01*
X773511Y227050D01*
X752689D01*
X751363Y225724D01*
G02X750770Y225754I-283J282D01*
G03X748363Y225647I-1164J-950D01*
G02X747700I-332J224D01*
G03X745007Y225198I-1243J-843D01*
G01X744967Y225050D01*
X731311D01*
X729650Y226711D01*
Y283289D01*
X731611Y285250D01*
X750311D01*
X752650Y287589D01*
Y300011D01*
X732611Y320050D01*
X717911D01*
X716750Y321211D01*
Y324839D01*
X758750Y366839D01*
Y395818D01*
X754811Y399757D01*
X748804D01*
X747250Y401311D01*
Y438189D01*
X756811Y447750D01*
X815689D01*
X819250Y444189D01*
Y415189D01*
X829750Y404689D01*
Y271291D01*
X825282Y266822D01*
X823750Y265314D01*
Y224750D01*
X776316D01*
G37*
%LPD*%
G75*
G36*
G01X305778Y340592D02*
G02X302756I-1511J0D01*
G01Y344093D01*
G02X305778Y344092I1511J-1D01*
G01Y340592D01*
G37*
G36*
G01X309078Y353192D02*
G02X306056I-1511J0D01*
G01Y356693D01*
G02X309078Y356692I1511J-1D01*
G01Y353192D01*
G37*
G36*
G01X305778Y365792D02*
G02X302756I-1511J0D01*
G01Y369293D01*
G02X305778Y369292I1511J-1D01*
G01Y365792D01*
G37*
G36*
G01X326670Y350371D02*
G02X329694I1512J0D01*
G01Y346870D01*
G02X326670Y346871I-1512J1D01*
G01Y350371D01*
G37*
G36*
G01X329694Y372018D02*
G02X326670I-1512J0D01*
G01Y375519D01*
G02X329694Y375518I1512J-1D01*
G01Y372018D01*
G37*
G36*
G01X305778Y315392D02*
G02X302756I-1511J0D01*
G01Y318893D01*
G02X305778Y318892I1511J-1D01*
G01Y315392D01*
G37*
G36*
G01X309078Y277592D02*
G02X306056I-1511J0D01*
G01Y281093D01*
G02X309078Y281092I1511J-1D01*
G01Y277592D01*
G37*
G36*
G01X305778Y290192D02*
G02X302756I-1511J0D01*
G01Y293693D01*
G02X305778Y293692I1511J-1D01*
G01Y290192D01*
G37*
G36*
G01X309078Y302792D02*
G02X306056I-1511J0D01*
G01Y306293D01*
G02X309078Y306292I1511J-1D01*
G01Y302792D01*
G37*
G36*
G01X329694Y296477D02*
G02X326670I-1512J0D01*
G01Y299978D01*
G02X329694Y299977I1512J-1D01*
G01Y296477D01*
G37*
G36*
G01Y321674D02*
G02X326670I-1512J0D01*
G01Y325175D01*
G02X329694Y325174I1512J-1D01*
G01Y321674D01*
G37*
G36*
G01X309078Y328092D02*
G02X306056I-1511J0D01*
G01Y331593D01*
G02X309078Y331592I1511J-1D01*
G01Y328092D01*
G37*
G36*
G01X302720Y268548D02*
G02X305742I1511J0D01*
G01Y265047D01*
G02X302720Y265048I-1511J1D01*
G01Y268548D01*
G37*
G36*
G01X849476Y314648D02*
X849477Y314647D01*
X852620Y311503D01*
X852622Y311501D01*
G02X850524Y309352I-1031J-1092D01*
G01X847352Y312524D01*
G02X849476Y314648I1057J1067D01*
G37*
G36*
G01X853976Y299148D02*
X853977Y299147D01*
X857120Y296003D01*
X857122Y296001D01*
G02X855024Y293852I-1031J-1092D01*
G01X851852Y297024D01*
G02X853976Y299148I1057J1067D01*
G37*
G36*
G01X847976Y293148D02*
X847977Y293147D01*
X851120Y290003D01*
X851122Y290001D01*
G02X849024Y287852I-1031J-1092D01*
G01X845852Y291024D01*
G02X847976Y293148I1057J1067D01*
G37*
G36*
G01X842476Y287648D02*
X842477Y287647D01*
X845620Y284503D01*
X845622Y284501D01*
G02X843524Y282352I-1031J-1092D01*
G01X840352Y285524D01*
G02X842476Y287648I1057J1067D01*
G37*
G36*
G01X844476Y274648D02*
X844477Y274647D01*
X847620Y271503D01*
X847622Y271501D01*
G02X845524Y269352I-1031J-1092D01*
G01X842352Y272524D01*
G02X844476Y274648I1057J1067D01*
G37*
G36*
G01X839524Y263552D02*
X836352Y266724D01*
G02X838476Y268848I1057J1067D01*
G01X838477Y268847D01*
X841620Y265703D01*
X841622Y265701D01*
G02X839524Y263552I-1031J-1092D01*
G37*
G36*
G01X832676Y262348D02*
X832677Y262347D01*
X835820Y259203D01*
X835822Y259201D01*
G02X833724Y257052I-1031J-1092D01*
G01X830552Y260224D01*
G02X832676Y262348I1057J1067D01*
G37*
G36*
G01X832012Y252729D02*
X832013Y252728D01*
X835156Y249584D01*
X835158Y249582D01*
G02X833060Y247433I-1031J-1092D01*
G01X829888Y250605D01*
G02X832012Y252729I1057J1067D01*
G37*
G36*
G01X336094Y334271D02*
G02X333070I-1512J0D01*
G01Y337772D01*
G02X336094Y337771I1512J-1D01*
G01Y334271D01*
G37*
G36*
G01Y359474D02*
G02X333070I-1512J0D01*
G01Y362975D01*
G02X336094Y362974I1512J-1D01*
G01Y359474D01*
G37*
G36*
G01X333070Y287284D02*
G02X336094I1512J0D01*
G01Y283783D01*
G02X333070Y283784I-1512J1D01*
G01Y287284D01*
G37*
G36*
G01X336094Y309074D02*
G02X333070I-1512J0D01*
G01Y312575D01*
G02X336094Y312574I1512J-1D01*
G01Y309074D01*
G37*
G36*
G01X466084Y149798D02*
Y145478D01*
X466093Y145450D01*
G02X462253I-1920J-568D01*
G01X462262Y145478D01*
Y149798D01*
X462253Y149826D01*
G02X466093I1920J568D01*
G01X466084Y149798D01*
G37*
G36*
G01X451912D02*
Y145478D01*
X451920Y145450D01*
G02X448080I-1920J-568D01*
G01X448088Y145478D01*
Y149798D01*
X448080Y149826D01*
G02X451920I1920J568D01*
G01X451912Y149798D01*
G37*
G36*
G01X437738D02*
Y145478D01*
X437747Y145450D01*
G02X433907I-1920J-568D01*
G01X433916Y145478D01*
Y149798D01*
X433907Y149826D01*
G02X437747I1920J568D01*
G01X437738Y149798D01*
G37*
G36*
G01X423564D02*
Y145478D01*
X423573Y145450D01*
G02X419733I-1920J-568D01*
G01X419742Y145478D01*
Y149798D01*
X419733Y149826D01*
G02X423573I1920J568D01*
G01X423564Y149798D01*
G37*
G36*
G01X473172Y145074D02*
Y140754D01*
X473180Y140726D01*
G02X469340I-1920J-568D01*
G01X469348Y140754D01*
Y145074D01*
X469340Y145102D01*
G02X473180I1920J568D01*
G01X473172Y145074D01*
G37*
G36*
G01X458998D02*
Y140754D01*
X459006Y140726D01*
G02X455166I-1920J-568D01*
G01X455174Y140754D01*
Y145074D01*
X455166Y145102D01*
G02X459006I1920J568D01*
G01X458998Y145074D01*
G37*
G36*
G01X444824D02*
Y140754D01*
X444833Y140726D01*
G02X440993I-1920J-568D01*
G01X441002Y140754D01*
Y145074D01*
X440993Y145102D01*
G02X444833I1920J568D01*
G01X444824Y145074D01*
G37*
G36*
G01X430652D02*
Y140754D01*
X430660Y140726D01*
G02X426820I-1920J-568D01*
G01X426828Y140754D01*
Y145074D01*
X426820Y145102D01*
G02X430660I1920J568D01*
G01X430652Y145074D01*
G37*
G36*
G01X466084Y135625D02*
Y131305D01*
X466093Y131277D01*
G02X462253I-1920J-568D01*
G01X462262Y131305D01*
Y135625D01*
X462253Y135653D01*
G02X466093I1920J568D01*
G01X466084Y135625D01*
G37*
G36*
G01X451912D02*
Y131305D01*
X451920Y131277D01*
G02X448080I-1920J-568D01*
G01X448088Y131305D01*
Y135625D01*
X448080Y135653D01*
G02X451920I1920J568D01*
G01X451912Y135625D01*
G37*
G36*
G01X437738D02*
Y131305D01*
X437747Y131277D01*
G02X433907I-1920J-568D01*
G01X433916Y131305D01*
Y135625D01*
X433907Y135653D01*
G02X437747I1920J568D01*
G01X437738Y135625D01*
G37*
G36*
G01X423564D02*
Y131305D01*
X423573Y131277D01*
G02X419733I-1920J-568D01*
G01X419742Y131305D01*
Y135625D01*
X419733Y135653D01*
G02X423573I1920J568D01*
G01X423564Y135625D01*
G37*
G36*
G01X473172Y130900D02*
Y126581D01*
X473180Y126553D01*
G02X469340I-1920J-568D01*
G01X469348Y126581D01*
Y130900D01*
X469340Y130928D01*
G02X473180I1920J568D01*
G01X473172Y130900D01*
G37*
G36*
G01X458998D02*
Y126581D01*
X459006Y126553D01*
G02X455166I-1920J-568D01*
G01X455174Y126581D01*
Y130900D01*
X455166Y130928D01*
G02X459006I1920J568D01*
G01X458998Y130900D01*
G37*
G36*
G01X444824D02*
Y126581D01*
X444833Y126553D01*
G02X440993I-1920J-568D01*
G01X441002Y126581D01*
Y130900D01*
X440993Y130928D01*
G02X444833I1920J568D01*
G01X444824Y130900D01*
G37*
G36*
G01X430652D02*
Y126581D01*
X430660Y126553D01*
G02X426820I-1920J-568D01*
G01X426828Y126581D01*
Y130900D01*
X426820Y130928D01*
G02X430660I1920J568D01*
G01X430652Y130900D01*
G37*
G36*
G01X522778Y149798D02*
Y145478D01*
X522786Y145450D01*
G02X518946I-1920J-568D01*
G01X518954Y145478D01*
Y149798D01*
X518946Y149826D01*
G02X522786I1920J568D01*
G01X522778Y149798D01*
G37*
G36*
G01X508604D02*
Y145478D01*
X508613Y145450D01*
G02X504773I-1920J-568D01*
G01X504782Y145478D01*
Y149798D01*
X504773Y149826D01*
G02X508613I1920J568D01*
G01X508604Y149798D01*
G37*
G36*
G01X529864Y145074D02*
Y140754D01*
X529873Y140726D01*
G02X526033I-1920J-568D01*
G01X526042Y140754D01*
Y145074D01*
X526033Y145102D01*
G02X529873I1920J568D01*
G01X529864Y145074D01*
G37*
G36*
G01X515690D02*
Y140754D01*
X515699Y140726D01*
G02X511859I-1920J-568D01*
G01X511868Y140754D01*
Y145074D01*
X511859Y145102D01*
G02X515699I1920J568D01*
G01X515690Y145074D01*
G37*
G36*
G01X522778Y135625D02*
Y131305D01*
X522786Y131277D01*
G02X518946I-1920J-568D01*
G01X518954Y131305D01*
Y135625D01*
X518946Y135653D01*
G02X522786I1920J568D01*
G01X522778Y135625D01*
G37*
G36*
G01X508604D02*
Y131305D01*
X508613Y131277D01*
G02X504773I-1920J-568D01*
G01X504782Y131305D01*
Y135625D01*
X504773Y135653D01*
G02X508613I1920J568D01*
G01X508604Y135625D01*
G37*
G36*
G01X529864Y130900D02*
Y126581D01*
X529873Y126553D01*
G02X526033I-1920J-568D01*
G01X526042Y126581D01*
Y130900D01*
X526033Y130928D01*
G02X529873I1920J568D01*
G01X529864Y130900D01*
G37*
G36*
G01X515690D02*
Y126581D01*
X515699Y126553D01*
G02X511859I-1920J-568D01*
G01X511868Y126581D01*
Y130900D01*
X511859Y130928D01*
G02X515699I1920J568D01*
G01X515690Y130900D01*
G37*
G36*
G01X551124Y149798D02*
Y145478D01*
X551132Y145450D01*
G02X547292I-1920J-568D01*
G01X547300Y145478D01*
Y149798D01*
X547292Y149826D01*
G02X551132I1920J568D01*
G01X551124Y149798D01*
G37*
G36*
G01X536950D02*
Y145478D01*
X536959Y145450D01*
G02X533119I-1920J-568D01*
G01X533128Y145478D01*
Y149798D01*
X533119Y149826D01*
G02X536959I1920J568D01*
G01X536950Y149798D01*
G37*
G36*
G01X558210Y145074D02*
Y140754D01*
X558219Y140726D01*
G02X554379I-1920J-568D01*
G01X554388Y140754D01*
Y145074D01*
X554379Y145102D01*
G02X558219I1920J568D01*
G01X558210Y145074D01*
G37*
G36*
G01X544038D02*
Y140754D01*
X544046Y140726D01*
G02X540206I-1920J-568D01*
G01X540214Y140754D01*
Y145074D01*
X540206Y145102D01*
G02X544046I1920J568D01*
G01X544038Y145074D01*
G37*
G36*
G01X551124Y135625D02*
Y131305D01*
X551132Y131277D01*
G02X547292I-1920J-568D01*
G01X547300Y131305D01*
Y135625D01*
X547292Y135653D01*
G02X551132I1920J568D01*
G01X551124Y135625D01*
G37*
G36*
G01X536950D02*
Y131305D01*
X536959Y131277D01*
G02X533119I-1920J-568D01*
G01X533128Y131305D01*
Y135625D01*
X533119Y135653D01*
G02X536959I1920J568D01*
G01X536950Y135625D01*
G37*
G36*
G01X558210Y130900D02*
Y126581D01*
X558219Y126553D01*
G02X554379I-1920J-568D01*
G01X554388Y126581D01*
Y130900D01*
X554379Y130928D01*
G02X558219I1920J568D01*
G01X558210Y130900D01*
G37*
G36*
G01X544038D02*
Y126581D01*
X544046Y126553D01*
G02X540206I-1920J-568D01*
G01X540214Y126581D01*
Y130900D01*
X540206Y130928D01*
G02X544046I1920J568D01*
G01X544038Y130900D01*
G37*
G36*
G01X703980Y104192D02*
G02X707438Y106044I1729J926D01*
G01X710371Y100567D01*
X710372Y100565D01*
G02X706932Y98680I-1711J-959D01*
G01X703980Y104192D01*
G37*
G36*
G01X712838Y104191D02*
G02X716296Y106045I1729J927D01*
G01X719230Y100567D01*
X719231Y100565D01*
G02X715791Y98679I-1711J-959D01*
G01X712838Y104191D01*
G37*
G36*
G01X715607Y114177D02*
X715602Y114206D01*
X713203Y118682D01*
X713183Y118703D01*
G02X716480Y120469I1384J1376D01*
G01X716485Y120440D01*
X718883Y115964D01*
X718904Y115944D01*
G02X715607Y114177I-1384J-1377D01*
G37*
G36*
G01X706748D02*
X706742Y114206D01*
X704345Y118682D01*
X704325Y118703D01*
G02X707622Y120469I1384J1376D01*
G01X707628Y120440D01*
X710024Y115964D01*
X710045Y115943D01*
G02X706748Y114177I-1384J-1376D01*
G37*
G36*
G01X636867D02*
X636862Y114206D01*
X634463Y118682D01*
X634443Y118703D01*
G02X637740Y120469I1384J1376D01*
G01X637745Y120440D01*
X640143Y115964D01*
X640164Y115944D01*
G02X636867Y114177I-1384J-1377D01*
G37*
G36*
G01X628882Y120469D02*
X628888Y120440D01*
X631284Y115964D01*
X631305Y115943D01*
G02X628008Y114177I-1384J-1376D01*
G01X628002Y114206D01*
X625605Y118682D01*
X625585Y118703D01*
G02X628882Y120469I1384J1376D01*
G37*
G36*
G01X636867Y99216D02*
X636862Y99245D01*
X634463Y103721D01*
X634443Y103742D01*
G02X637740Y105508I1384J1376D01*
G01X637745Y105479D01*
X640143Y101003D01*
X640164Y100983D01*
G02X636867Y99216I-1384J-1377D01*
G37*
G36*
G01X628882Y105508D02*
X628888Y105479D01*
X631284Y101003D01*
X631305Y100982D01*
G02X628008Y99216I-1384J-1376D01*
G01X628002Y99245D01*
X625605Y103721D01*
X625585Y103742D01*
G02X628882Y105508I1384J1376D01*
G37*
G36*
G01X715614Y84226D02*
X715608Y84253D01*
X713181Y88783D01*
X713161Y88803D01*
G02X716473Y90577I1406J1354D01*
G01X716479Y90550D01*
X718907Y86019D01*
X718927Y85999D01*
G02X715614Y84226I-1407J-1353D01*
G37*
G36*
G01X706748Y84256D02*
X706742Y84285D01*
X704346Y88760D01*
X704325Y88780D01*
G02X707622Y90547I1384J1377D01*
G01X707628Y90518D01*
X710025Y86043D01*
X710045Y86022D01*
G02X706748Y84256I-1384J-1376D01*
G37*
G36*
G01X636874Y84226D02*
X636868Y84253D01*
X634441Y88783D01*
X634421Y88803D01*
G02X637733Y90577I1406J1354D01*
G01X637739Y90550D01*
X640167Y86019D01*
X640187Y85999D01*
G02X636874Y84226I-1407J-1353D01*
G37*
G36*
G01X628882Y90547D02*
X628888Y90518D01*
X631285Y86043D01*
X631305Y86022D01*
G02X628008Y84256I-1384J-1376D01*
G01X628002Y84285D01*
X625606Y88760D01*
X625585Y88780D01*
G02X628882Y90547I1384J1377D01*
G37*
G36*
G01X715607Y69295D02*
X715602Y69324D01*
X713203Y73800D01*
X713183Y73821D01*
G02X716480Y75587I1384J1376D01*
G01X716485Y75558D01*
X718883Y71082D01*
X718904Y71062D01*
G02X715607Y69295I-1384J-1377D01*
G37*
G36*
G01X706748D02*
X706742Y69324D01*
X704345Y73800D01*
X704325Y73821D01*
G02X707622Y75587I1384J1376D01*
G01X707628Y75558D01*
X710024Y71082D01*
X710045Y71061D01*
G02X706748Y69295I-1384J-1376D01*
G37*
G36*
G01X636867D02*
X636862Y69324D01*
X634463Y73800D01*
X634443Y73821D01*
G02X637740Y75587I1384J1376D01*
G01X637745Y75558D01*
X640143Y71082D01*
X640164Y71062D01*
G02X636867Y69295I-1384J-1377D01*
G37*
G36*
G01X628882Y75587D02*
X628888Y75558D01*
X631284Y71082D01*
X631305Y71061D01*
G02X628008Y69295I-1384J-1376D01*
G01X628002Y69324D01*
X625605Y73800D01*
X625585Y73821D01*
G02X628882Y75587I1384J1376D01*
G37*
G36*
G01X796849Y298753D02*
G02Y295733I0J-1510D01*
G01X793699D01*
G02X793700Y298753I1J1510D01*
G01X796849D01*
G37*
G36*
G01X781670Y347206D02*
X781669Y347207D01*
X779234Y349642D01*
X779232Y349644D01*
G02X781330Y351794I1031J1093D01*
G01X783794Y349330D01*
G02X781670Y347206I-1057J-1067D01*
G37*
G36*
G01X764148Y351494D02*
X766612Y349030D01*
G02X764488Y346906I-1057J-1067D01*
G01X764487Y346907D01*
X762052Y349342D01*
X762050Y349344D01*
G02X764148Y351494I1031J1093D01*
G37*
G36*
G01X753430Y344794D02*
X755894Y342330D01*
G02X753770Y340206I-1057J-1067D01*
G01X753769Y340207D01*
X751334Y342642D01*
X751332Y342644D01*
G02X753430Y344794I1031J1093D01*
G37*
G36*
G01X793570Y335406D02*
X793569Y335407D01*
X791134Y337842D01*
X791132Y337844D01*
G02X793230Y339994I1031J1093D01*
G01X795694Y337530D01*
G02X793570Y335406I-1057J-1067D01*
G37*
G36*
G01X776248Y339494D02*
X778712Y337030D01*
G02X776588Y334906I-1057J-1067D01*
G01X776587Y334907D01*
X774152Y337342D01*
X774150Y337344D01*
G02X776248Y339494I1031J1093D01*
G37*
G36*
G01X803770Y333106D02*
X803769Y333107D01*
X801334Y335542D01*
X801332Y335544D01*
G02X803430Y337694I1031J1093D01*
G01X805894Y335230D01*
G02X803770Y333106I-1057J-1067D01*
G37*
G36*
G01X747330Y333794D02*
X749794Y331330D01*
G02X747670Y329206I-1057J-1067D01*
G01X747669Y329207D01*
X745234Y331642D01*
X745232Y331644D01*
G02X747330Y333794I1031J1093D01*
G37*
G36*
G01X765370Y328306D02*
X765369Y328307D01*
X762934Y330742D01*
X762932Y330744D01*
G02X765030Y332894I1031J1093D01*
G01X767494Y330430D01*
G02X765370Y328306I-1057J-1067D01*
G37*
G36*
G01X769908Y294122D02*
X769913Y290947D01*
G02X767276Y290250I-1410J-2D01*
G03X766580I-348J-197D01*
G02X763943Y290931I-1227J695D01*
G01X763915Y294089D01*
G02X766556Y294789I1410J13D01*
G03X767257Y294794I349J195D01*
G02X769908Y294126I1241J-670D01*
G01Y294122D01*
G37*
G36*
G01X779362Y290928D02*
G02X776725Y290250I-1410J17D01*
G03X776029I-348J-197D01*
G02X773392Y290959I-1227J695D01*
G01X773425Y294103D01*
G02X776062Y294782I1410J-15D01*
G03X776759Y294783I348J197D01*
G02X779399Y294076I1230J-690D01*
G01X779362Y290928D01*
G37*
G36*
G01X760464Y290945D02*
G02X757827Y290249I-1410J-1D01*
G03X757132I-348J-198D01*
G02X754495Y290944I-1227J695D01*
G01Y294093D01*
G02X757132Y294788I1410J0D01*
G03X757828I348J197D01*
G02X760465Y294093I1227J-694D01*
G01X760464Y290945D01*
G37*
G36*
G01X788818Y294071D02*
X788814Y292330D01*
G03X789493Y292042I400J-1D01*
G02X790545Y292469I1052J-1082D01*
G01X793694D01*
G02X794830Y289964I0J-1510D01*
G03X795130Y289301I301J-263D01*
G01X796845Y289294D01*
G02X796833Y286274I-6J-1510D01*
G01X795125Y286281D01*
G03X794820Y285620I-2J-400D01*
G02X795185Y284639I-1145J-984D01*
G01Y284634D01*
X795189Y281510D01*
G02X794829Y280529I-1510J-2D01*
G03X795134Y279870I305J-259D01*
G01X796865Y279874D01*
G02X796871Y276854I3J-1510D01*
G01X795176Y276850D01*
G03X794876Y276188I2J-400D01*
G02X795247Y275169I-1139J-992D01*
G01X795192Y272037D01*
G02X794817Y271067I-1510J26D01*
G03X795121Y270403I300J-264D01*
G01X796835Y270420D01*
G02X796865Y267400I15J-1510D01*
G01X795135Y267383D01*
G03X794832Y266726I4J-400D01*
G02X795184Y265770I-1158J-969D01*
G01X795209Y262646D01*
G02X792189Y262622I-1510J-12D01*
G01X792164Y265745D01*
G02X792807Y266994I1510J13D01*
G03X792809Y267648I-229J328D01*
G02X792849Y270138I874J1231D01*
G03Y270804I-221J333D01*
G02X792172Y272091I833J1260D01*
G01X792227Y275222D01*
G02X792865Y276429I1510J-26D01*
G03X792853Y277091I-230J327D01*
G02X792823Y279604I822J1266D01*
G03X792824Y280263I-226J330D01*
G02X792169Y281506I855J1245D01*
G01X792165Y284634D01*
G02X792838Y285893I1510J2D01*
G03X792844Y286555I-221J333D01*
G02X792563Y288787I859J1242D01*
G03X792261Y289449I-302J262D01*
G01X790544D01*
G02X789259Y290168I1J1510D01*
G03X788583Y290176I-341J-210D01*
G02X786174Y290250I-1182J769D01*
G03X785478I-348J-197D01*
G02X782841Y290947I-1227J695D01*
G01X782848Y294067D01*
G02X785483Y294763I1410J-3D01*
G03X786179Y294765I347J198D01*
G02X788818Y294071I1229J-691D01*
G37*
G54D47*
X305906Y182874D03*
G54D52*
X201801Y684252D03*
X225601D03*
G54D48*
X305906Y388386D03*
G54D41*
X103346Y34449D03*
X56102Y24606D03*
X590300Y574400D03*
G54D43*
X18700Y54650D03*
X901000Y21400D03*
X902500Y676000D03*
G54D53*
X488838Y137225D03*
G54D54*
Y164744D03*
G54D45*
X90157Y413583D03*
X309055Y157677D03*
G54D46*
X309252Y413583D03*
G54D55*
X652756Y180000D03*
G54D42*
X89764Y238386D03*
G54D50*
X865353Y332598D03*
G54D44*
X70866Y98425D03*
X875984Y433071D03*
X612205D03*
G54D51*
X163189Y669291D03*
G54D49*
X875985Y59055D03*
G54D27*
X339331Y49803D03*
X360669Y91929D03*
G54D14*
X38590Y55260D03*
X30270Y48330D03*
X31100Y458733D03*
X26576Y457406D03*
X34132Y521245D03*
X34175Y526969D03*
X64277Y502177D03*
X75399Y502179D03*
X69904Y502077D03*
X41250Y494600D03*
X49600Y496050D03*
X55300Y495600D03*
X62276Y550493D03*
X28800Y549474D03*
X29158Y543855D03*
X29058Y538228D03*
X28782Y555119D03*
X29165Y532612D03*
X33697Y560866D03*
X37660Y566400D03*
X42597Y571789D03*
X71002Y577013D03*
X67853Y573865D03*
X75197Y572437D03*
X64701Y570716D03*
Y564416D03*
X67853Y558117D03*
X61100Y546700D03*
X64400Y539000D03*
X67852Y586463D03*
Y583313D03*
X74151Y545516D03*
X74498Y551757D03*
X71002Y539219D03*
X74076Y535966D03*
X75508Y542198D03*
X71002Y542368D03*
X67852Y539219D03*
X71002Y545518D03*
Y558117D03*
X74152Y567565D03*
X71002D03*
Y564396D03*
X74152Y580163D03*
Y577013D03*
X71002Y561266D03*
X67853Y564416D03*
X75066Y563235D03*
X71002Y554967D03*
X67853D03*
X78276Y545566D03*
X67853Y542368D03*
X71002Y548668D03*
X53302Y567317D03*
X59200Y582200D03*
X64884Y650984D03*
X38550Y617950D03*
X50700Y664000D03*
X50800Y667900D03*
X40309Y660700D03*
X71850Y698900D03*
X76100Y697100D03*
X97600Y54810D03*
X89070Y62600D03*
X114390Y453185D03*
X108300Y435900D03*
X118108Y453159D03*
X121826Y453156D03*
X128968Y452741D03*
X125353Y452385D03*
X132109Y451199D03*
X136021Y451394D03*
X127812Y445066D03*
X107100Y497300D03*
X97926Y502300D03*
X86699D03*
X81094Y502166D03*
X138900Y525999D03*
X135012Y510200D03*
X119400Y511500D03*
X132100Y493000D03*
X133152Y484074D03*
X105350Y511850D03*
X114070Y481948D03*
X118900Y522000D03*
X138000Y485900D03*
X102700Y507100D03*
X116500Y477000D03*
X144500Y489500D03*
X114500Y490000D03*
X101800Y493000D03*
X137050Y476346D03*
X132774Y497000D03*
X89899Y558115D03*
X86750Y573864D03*
X89899D03*
X86750Y567565D03*
X89899Y564415D03*
X106272Y547370D03*
X94473Y547093D03*
X89901Y587466D03*
X93048Y577014D03*
X108371Y577258D03*
X136990Y535235D03*
X86750Y542368D03*
X126337Y554085D03*
X130311Y546700D03*
X81276Y548766D03*
X119605Y548705D03*
X86750Y539218D03*
X83600Y545518D03*
X89899D03*
X127300Y543200D03*
X89899Y539218D03*
X117200Y546300D03*
X83600Y539219D03*
X86750Y545518D03*
X122600Y557480D03*
X86750Y554965D03*
X130607Y569636D03*
X86750Y558115D03*
X126347Y569556D03*
X83600Y551817D03*
X117400Y567650D03*
X83600Y573865D03*
X86750Y586463D03*
Y583313D03*
X83601Y580164D03*
X89899Y577014D03*
X86750D03*
X83600Y564415D03*
X86750D03*
X83600Y561265D03*
X96570Y581730D03*
X86750Y551815D03*
X123300Y530300D03*
X133800Y528500D03*
X123200Y534600D03*
X143500Y529000D03*
X93744Y542019D03*
X133554Y537374D03*
X96371Y534124D03*
X101400Y606300D03*
X97800D03*
X137210Y622030D03*
X134030Y620760D03*
X130630Y620900D03*
X101500Y597000D03*
X85500Y628500D03*
X122750Y616950D03*
X122000Y628700D03*
X144800Y657900D03*
X136100Y656300D03*
X125100Y656700D03*
X123370Y606700D03*
X119600D03*
X127401Y606930D03*
X123500Y613100D03*
X93053Y606734D03*
X142447Y611714D03*
X119000Y633200D03*
X120500Y651800D03*
X134650Y612900D03*
X144750Y606350D03*
X141971Y624700D03*
X98200Y616900D03*
X129800Y630700D03*
X105600Y597000D03*
X105400Y601300D03*
X104600Y609900D03*
X105600Y605900D03*
X104600Y614000D03*
X104500Y618800D03*
X117050Y602000D03*
X116200Y611600D03*
X116023Y607423D03*
X119400Y614100D03*
X116500Y621000D03*
X116400Y616900D03*
X130800Y606700D03*
X138500Y637900D03*
X130500Y638600D03*
X134700D03*
X129903Y634500D03*
X111300Y705500D03*
X106879Y707245D03*
X125376Y701124D03*
X106355Y710745D03*
X106635Y701465D03*
X84600Y688000D03*
X119849Y709715D03*
X146301Y460200D03*
X197085Y459899D03*
X190278Y459865D03*
X193686Y459799D03*
X176000Y460200D03*
X172200Y460100D03*
X157496Y461248D03*
X166600Y509800D03*
X166700Y499800D03*
X146263Y468562D03*
X203307Y506400D03*
X179000Y499800D03*
X203500Y513500D03*
X186735Y463748D03*
X207500Y503000D03*
X191418Y509981D03*
X170870Y492270D03*
X158000Y480700D03*
X146143Y481057D03*
X175100Y477000D03*
X187000Y499500D03*
X146500Y492500D03*
X183300Y493100D03*
X145400Y524046D03*
X176100Y473200D03*
X174700Y513900D03*
X182300Y509600D03*
X184780Y526990D03*
X187167Y513167D03*
X191100Y513367D03*
X154500Y487000D03*
X178869Y509793D03*
X209800Y478500D03*
X205447Y487762D03*
X158290Y502380D03*
X182874Y523590D03*
X205516Y467968D03*
X170700Y509800D03*
X170900Y500000D03*
X165900Y524100D03*
X209256Y467946D03*
X172100Y467300D03*
X176800Y492200D03*
X175805Y524073D03*
X206180Y509524D03*
X191100Y526000D03*
X195149Y513751D03*
X150500Y493000D03*
X190950Y482100D03*
X196200Y482600D03*
X200100Y491700D03*
X146216Y486045D03*
X196243Y486782D03*
X159480Y506590D03*
X155540Y506510D03*
X195300Y498900D03*
X195379Y510158D03*
X150162Y525937D03*
X148527Y519491D03*
X191725Y523074D03*
X195300Y529400D03*
X148409Y575672D03*
X144876Y590854D03*
X148409Y579353D03*
X144876Y587173D03*
X203610Y529397D03*
X168390Y532060D03*
X184830Y529960D03*
X149419Y535654D03*
X191200Y529400D03*
X199400D03*
X208000Y529300D03*
X149242Y531080D03*
X152584Y532922D03*
X152415Y540014D03*
X194490Y645390D03*
X171020Y611020D03*
X200610Y639611D03*
X207900Y645600D03*
X169000Y640300D03*
X184967Y643983D03*
X200560Y635100D03*
X170940Y614400D03*
X191110Y611050D03*
X178140Y630330D03*
X196249Y630091D03*
X199400Y628646D03*
X151550Y629800D03*
X163200Y610070D03*
X160420Y610170D03*
X184050Y629500D03*
X181176Y627600D03*
X209093Y615849D03*
X166690Y615060D03*
X166600Y617850D03*
X195900Y649350D03*
X203400Y649600D03*
X146800Y629900D03*
X180700Y640460D03*
X204800Y617440D03*
X204642Y621140D03*
X177300Y626800D03*
X204150Y645180D03*
X199600Y650100D03*
X192960Y628510D03*
X187900Y628500D03*
X152700Y640800D03*
X161000Y634300D03*
X157200Y634200D03*
X196855Y698355D03*
X151130Y703440D03*
X148249Y695765D03*
X191766Y679920D03*
X202800Y660900D03*
X189000Y659900D03*
X162100Y711215D03*
X151949Y691715D03*
X175233Y704382D03*
X163349Y702715D03*
X150849Y710215D03*
X163260Y706988D03*
X169070Y696220D03*
X159519Y694455D03*
X193500Y663000D03*
X200400Y694700D03*
X196900Y661350D03*
X206300Y661100D03*
X181300Y679100D03*
X185100Y705600D03*
X184800Y709300D03*
X190200Y671000D03*
X187500Y673100D03*
X275100Y460300D03*
X259000Y453900D03*
X251700Y443600D03*
X268900Y445150D03*
X244700Y451200D03*
X236100Y445100D03*
X239300Y443800D03*
X243000D03*
X247900Y445300D03*
X260600Y442600D03*
X250500Y451300D03*
X224500Y445600D03*
X254900Y453900D03*
X232200Y445600D03*
X275500Y466200D03*
X211700Y513500D03*
X220100Y513400D03*
X211196Y487762D03*
X222600Y503500D03*
X246000Y516670D03*
X213100Y476300D03*
X261200Y525400D03*
X242500Y523500D03*
X254500Y509600D03*
X213100Y472900D03*
X275200Y474500D03*
X258100Y516400D03*
X227500Y512200D03*
X265148Y524595D03*
X228700Y490717D03*
X230700Y486658D03*
X249050Y527150D03*
X249640Y495080D03*
X234700Y490900D03*
X258381Y509498D03*
X225914Y523051D03*
X231800Y512100D03*
X223600Y512400D03*
X213359Y480489D03*
X238400Y511300D03*
X265274Y509512D03*
X267800Y479900D03*
X222500Y536161D03*
X211500Y529400D03*
X230900Y581600D03*
X229800Y593200D03*
X247400Y589600D03*
X252593Y547650D03*
X261900Y591300D03*
X247100Y582400D03*
X246611Y551511D03*
X246484Y537139D03*
X269900Y567619D03*
X234943Y565199D03*
X254600Y567700D03*
X260731Y561264D03*
X260741Y542700D03*
X264333Y528926D03*
X254905Y555761D03*
X258528Y555161D03*
X259100Y567706D03*
X257000Y571700D03*
X223900Y531200D03*
X228100Y545500D03*
X228800Y542100D03*
X228313Y552169D03*
X262000Y586900D03*
X257851Y580080D03*
X270145Y557526D03*
X261308Y583388D03*
X237100Y590000D03*
X257700Y586400D03*
X261500Y576400D03*
X261600Y580000D03*
X257891Y563786D03*
X257600Y576500D03*
X233607Y557671D03*
X254500Y575070D03*
X261100Y571600D03*
X234800Y572000D03*
X232400Y533200D03*
X248900Y545700D03*
X267957Y537304D03*
X274623Y578896D03*
X271357Y537253D03*
X233036Y550942D03*
X213800Y631200D03*
X212308Y605949D03*
X229796Y610104D03*
X270000Y602400D03*
X255228Y631071D03*
X255648Y626127D03*
X245300Y635700D03*
X254199Y603443D03*
X254600Y597100D03*
X229137Y634881D03*
X266857Y634343D03*
X256001Y612347D03*
X258869Y603050D03*
X266571Y608619D03*
X275470Y608480D03*
X270400Y622870D03*
X264040Y648370D03*
X219200Y647200D03*
X221900Y630800D03*
X218800Y635600D03*
X230900Y649100D03*
X211706Y645349D03*
X247725Y656375D03*
X246500Y601500D03*
X234000Y629576D03*
X218200Y651400D03*
X248450Y609900D03*
X266847Y626253D03*
X229063Y638560D03*
X216600Y658400D03*
X274800Y635000D03*
X222950Y647900D03*
X226471Y649129D03*
X243322Y597509D03*
X251314Y598106D03*
X251338Y601506D03*
X258550Y606527D03*
Y610096D03*
X215606Y645806D03*
X229500Y631500D03*
X212900Y619201D03*
X273714Y629870D03*
X266571Y630071D03*
X245100Y647200D03*
X272200Y648550D03*
X221238Y620524D03*
X234205Y598743D03*
X233258Y595693D03*
X232130Y612950D03*
X251900Y609600D03*
X259777Y638873D03*
X242000Y656400D03*
X255733Y622329D03*
X253196Y706062D03*
X261248Y700086D03*
X272050Y711810D03*
X267880Y704920D03*
X262634Y711233D03*
X266400Y675349D03*
X265000Y662574D03*
X247825Y670375D03*
X235100Y679921D03*
X221575Y695400D03*
X242000Y693400D03*
X237509Y674915D03*
X266200Y679400D03*
X268384Y662909D03*
X263700Y723500D03*
X264700Y700000D03*
X214270Y695095D03*
X275300Y668749D03*
X217638Y695562D03*
X235000Y692900D03*
X262323Y716917D03*
X255200Y680950D03*
X239400Y677900D03*
X266300Y692574D03*
X311715Y20397D03*
X310353Y62159D03*
X326553Y34687D03*
X340297Y117548D03*
X341484Y110328D03*
X339232Y113960D03*
X338743Y122894D03*
X305700Y197600D03*
X295841Y176793D03*
X323582Y179064D03*
X299107Y177740D03*
X295462Y173414D03*
X304231Y265048D03*
Y261048D03*
X322426Y223731D03*
Y227531D03*
X321197Y254433D03*
X322426Y231331D03*
X321782Y215974D03*
X306446Y247874D03*
X305382Y227474D03*
X305498Y213824D03*
X305703Y202165D03*
X306407Y206057D03*
X305782Y230874D03*
X335082Y231574D03*
X322301Y220009D03*
X305782Y217274D03*
X305682Y224074D03*
X305782Y220674D03*
X305454Y244461D03*
X334998Y255520D03*
X305373Y251101D03*
X334998Y259033D03*
X306412Y254339D03*
X335060Y262516D03*
X305882Y234274D03*
X305772Y237673D03*
X321700Y246000D03*
X321600Y250000D03*
X305781Y241076D03*
X334582Y291284D03*
Y287284D03*
Y283784D03*
Y279784D03*
X307567Y331592D03*
Y328092D03*
Y324092D03*
X304267Y322892D03*
Y318892D03*
Y315392D03*
Y311392D03*
X307567Y310292D03*
Y306292D03*
Y302792D03*
Y298792D03*
X304267Y297692D03*
Y293692D03*
Y290192D03*
Y286192D03*
X334582Y330271D03*
X328182Y329174D03*
Y325174D03*
Y321674D03*
Y317674D03*
X334582Y316574D03*
Y312574D03*
Y309074D03*
Y305074D03*
X328182Y303977D03*
Y299977D03*
Y296477D03*
Y292477D03*
X307567Y285092D03*
Y281092D03*
Y277592D03*
Y273592D03*
X304231Y272548D03*
Y268548D03*
X321281Y266486D03*
X321432Y279090D03*
X321882Y291874D03*
Y304374D03*
X321432Y316885D03*
Y329484D03*
X328913Y274414D03*
X334017Y272000D03*
X337808Y288709D03*
X304267Y373292D03*
Y369292D03*
Y365792D03*
Y361792D03*
X307567Y360692D03*
Y356692D03*
Y353192D03*
Y349192D03*
X304267Y348092D03*
Y344092D03*
Y340592D03*
Y336592D03*
X307567Y335592D03*
X328182Y379518D03*
Y375518D03*
Y372018D03*
Y368018D03*
X334582Y366974D03*
Y362974D03*
Y359474D03*
Y355474D03*
Y341771D03*
Y337771D03*
Y334271D03*
X328182Y354371D03*
Y350371D03*
Y346871D03*
Y342871D03*
X321432Y342082D03*
Y354681D03*
X321202Y376887D03*
X321432Y367279D03*
X335982Y390874D03*
X303680Y380972D03*
X316900Y384100D03*
X319679Y387121D03*
X314000Y390500D03*
X335800Y379800D03*
X338800Y435100D03*
X281200Y453500D03*
X333850Y458400D03*
X286700Y457500D03*
X323759Y435145D03*
X327159Y435201D03*
X276634Y498311D03*
X307364Y505750D03*
X321976D03*
X329035Y519325D03*
X293793Y521556D03*
X321208Y519411D03*
X286797Y516522D03*
X308687Y519193D03*
X302307Y505799D03*
X298907Y505851D03*
X292100Y516000D03*
X297400Y517981D03*
X336600Y504500D03*
X336800Y499967D03*
X325400Y505800D03*
X282403Y474500D03*
X282400Y470200D03*
X328200Y511600D03*
X331200Y508900D03*
X299448Y511300D03*
X277603Y479948D03*
X332821Y515415D03*
X278400Y463300D03*
X280939Y504705D03*
X314400Y505750D03*
X334650Y508900D03*
X300476Y546907D03*
X285800Y549394D03*
X303100Y587000D03*
X292850Y586100D03*
X293271Y557248D03*
X327110Y583660D03*
X316680Y583527D03*
X337899Y587874D03*
X285982Y542502D03*
X310350Y538293D03*
X330860Y551744D03*
X325447Y536109D03*
X291800Y576708D03*
X333800Y534830D03*
X329840Y572710D03*
X337550Y534619D03*
X295824Y578108D03*
X325475Y572818D03*
X323659Y557310D03*
X334900Y586100D03*
X333512Y553888D03*
X281610Y590260D03*
X324200Y565300D03*
X281490Y586862D03*
X337300Y583000D03*
X336367Y549943D03*
X294107Y560762D03*
X330729Y557268D03*
X298000Y561000D03*
X327059Y557247D03*
X288309Y566467D03*
X328580Y568120D03*
X291000Y570810D03*
X320954Y572631D03*
X277048Y590470D03*
X319529Y562413D03*
X319252Y566509D03*
X285912Y538750D03*
X318736Y549697D03*
X280100Y532100D03*
X322889Y529380D03*
X322843Y533254D03*
X279664Y535473D03*
X328771Y549035D03*
X332808Y547575D03*
X332834Y543993D03*
X337346Y545100D03*
X341316Y545000D03*
X282000Y583500D03*
X298514Y550184D03*
X293087Y530571D03*
X325687Y551368D03*
X319430Y557486D03*
X276839Y582309D03*
X277441Y539882D03*
X308200Y593153D03*
X310292Y532128D03*
X339081Y628173D03*
X290300Y636900D03*
X290500Y640600D03*
X331655Y603405D03*
X339822Y609785D03*
X339847Y620281D03*
X305470Y623734D03*
X278546Y633450D03*
X281900Y640900D03*
X317600Y603300D03*
X339266Y658409D03*
X340100Y631417D03*
X339751Y616882D03*
Y613185D03*
X335036Y603039D03*
X338733D03*
X325300Y648700D03*
X294500Y630600D03*
X298100Y630650D03*
X330400Y644300D03*
X334700Y644500D03*
X302459Y599531D03*
X306100Y599500D03*
X306231Y602898D03*
X302180Y603084D03*
X335100Y650600D03*
X338100Y635800D03*
X331718Y655832D03*
X329100Y650700D03*
X317689Y599833D03*
X287200Y632600D03*
X290900Y630900D03*
X278769Y700697D03*
X318400Y678400D03*
X325900Y678500D03*
X281400Y708200D03*
X281500Y712200D03*
X279400Y686400D03*
X294804Y695204D03*
X296800Y665081D03*
X311600Y670354D03*
X319600Y670450D03*
X293300Y679700D03*
X340500Y711750D03*
X335750Y664700D03*
X288700Y667900D03*
X340100Y718200D03*
X327250Y701500D03*
X327162Y696776D03*
X282300Y700100D03*
X316000Y671850D03*
X276800Y697925D03*
X338669Y691580D03*
X339804Y679030D03*
X340403Y699400D03*
X340300Y703100D03*
X336200Y677000D03*
X289700Y678830D03*
X280646Y717540D03*
X276100Y677700D03*
X300100Y670300D03*
X304700Y668500D03*
X298570Y743670D03*
X306470Y743570D03*
X278553Y740020D03*
X287620Y737300D03*
X290000Y727000D03*
X313873Y735907D03*
X314100Y739300D03*
X380500Y33500D03*
Y30000D03*
X384000D03*
X381173Y49058D03*
X381156Y54116D03*
X375200Y63400D03*
X370870Y45605D03*
X368059Y57759D03*
X354798Y22452D03*
X375300Y72150D03*
X374844Y87900D03*
X375000Y107300D03*
X393206Y77614D03*
X374844Y76700D03*
X362000Y124000D03*
X386759Y79693D03*
X390456D03*
X342539Y120370D03*
X369253Y88733D03*
X367287Y77118D03*
X381269Y94981D03*
X384666Y93741D03*
X349206Y129948D03*
X390964Y87226D03*
X388700Y89800D03*
X349072Y193574D03*
X400212Y154732D03*
X400351Y165605D03*
X349072Y189774D03*
X371775Y200577D03*
X348082Y186224D03*
X370149Y167337D03*
X370882Y163688D03*
X387202Y164664D03*
X387393Y160859D03*
X404727Y162141D03*
X392102Y175384D03*
X400205Y158209D03*
Y161906D03*
X392458Y171676D03*
X400430Y147190D03*
X362197Y222068D03*
X362722Y237674D03*
X347482Y254774D03*
X341882Y251064D03*
X342885Y276301D03*
X342958Y279701D03*
X383170Y329807D03*
X344732Y393882D03*
Y390274D03*
X383285Y347114D03*
X383327Y343379D03*
X396561Y351418D03*
X346600Y375000D03*
X344732Y386874D03*
X365100Y348300D03*
X372491Y378025D03*
X365200Y344400D03*
X378492Y378175D03*
X383030Y352442D03*
X367358Y372531D03*
X367471Y369120D03*
X360100Y453500D03*
X342700Y435200D03*
X350491Y453809D03*
X372000Y452100D03*
X369900Y458700D03*
X387450Y454558D03*
X387396Y458126D03*
X384395Y449114D03*
X374700Y460300D03*
X350400Y459000D03*
X381106Y441241D03*
X350400Y462400D03*
X374650Y456771D03*
X346500Y435200D03*
X364500Y453700D03*
X367400Y461200D03*
X355400Y453800D03*
X357900Y450800D03*
X369000Y512700D03*
X345497Y527644D03*
X355300Y510100D03*
X353300Y521400D03*
X344700Y509000D03*
X368721Y525271D03*
X371900Y481548D03*
X365800Y498300D03*
X344500Y500300D03*
X363500Y464700D03*
X372000Y477710D03*
X355300Y502700D03*
X357700Y499000D03*
X400080Y500854D03*
X384849Y525499D03*
Y521681D03*
X355300Y506100D03*
Y513500D03*
X386367Y474700D03*
X400080Y519500D03*
Y491107D03*
Y523903D03*
Y528243D03*
X389349Y480100D03*
X381986Y515631D03*
X374751Y485636D03*
X374715Y498722D03*
X366950Y464700D03*
X390229Y508189D03*
X341500Y520400D03*
X373699Y521160D03*
X359100Y503200D03*
X374800Y516912D03*
X387450Y467000D03*
X389288Y483500D03*
X358800Y478000D03*
X373800Y503000D03*
X370900Y464700D03*
X378267Y496100D03*
X349088Y500296D03*
X373500Y540305D03*
X393912Y568499D03*
X351600Y540600D03*
X348314Y585614D03*
X385600Y529107D03*
X372600Y576207D03*
X374292Y580300D03*
X355012Y582324D03*
X363008Y547309D03*
X371227Y566830D03*
X384950Y560496D03*
X352279Y580294D03*
X346303Y591947D03*
X386723Y544565D03*
X342440Y571770D03*
X361900Y570800D03*
X369500Y542900D03*
X388641Y549747D03*
X400093Y536351D03*
X399726Y562327D03*
X399946Y558677D03*
X344163Y553395D03*
X345259Y557566D03*
X391993Y582154D03*
X362300Y555200D03*
X343840Y566440D03*
X348300Y565400D03*
X364900Y585171D03*
X364964Y588771D03*
X372939Y559838D03*
X346590Y572090D03*
X350278Y572306D03*
X366270Y563400D03*
X373222Y535938D03*
X370247Y546218D03*
X370223Y549965D03*
X384950Y551876D03*
Y555276D03*
X383056Y563675D03*
X400060Y554743D03*
X393912Y571899D03*
X393910Y575305D03*
X341493Y541250D03*
X393912Y578705D03*
X348600Y643500D03*
X344564Y628104D03*
X379400Y641800D03*
X385163Y641354D03*
X342133Y603008D03*
X391150Y613429D03*
X350500Y647600D03*
X355000Y652160D03*
X374200Y645871D03*
X370200Y636400D03*
X359036Y635900D03*
X359258Y596820D03*
X383300Y600600D03*
X384410Y633530D03*
X364014Y593996D03*
X343797Y631417D03*
X381967Y616123D03*
X361227Y630300D03*
X377700Y595000D03*
X383199Y623168D03*
X382438Y608755D03*
X384158Y638105D03*
X380443D03*
X400064Y652598D03*
X384300Y619925D03*
X354102Y660666D03*
X392720Y697500D03*
X376342Y711260D03*
X358296Y672460D03*
X346465Y703185D03*
X364200Y713100D03*
X369600Y693400D03*
X351100Y712100D03*
X384220Y700618D03*
X367600Y696800D03*
X396166Y692630D03*
X343200Y667600D03*
X389999Y664697D03*
X367700Y685450D03*
X343338Y679236D03*
X399999Y673422D03*
X396419Y679708D03*
X398983Y706749D03*
X382308Y665022D03*
X396419Y686586D03*
X372350Y698400D03*
X399093Y703350D03*
X380300Y703000D03*
X399154Y699950D03*
X341900Y690350D03*
X346600Y714500D03*
X346000Y684300D03*
X383800Y688400D03*
X380387Y685261D03*
X392500Y673500D03*
X392800Y677600D03*
X341934Y662794D03*
X378595Y664960D03*
X388626Y715509D03*
X392500Y692500D03*
X355298Y711750D03*
X396419Y683186D03*
X459950Y58000D03*
X469058Y49156D03*
X439200Y22100D03*
X439549Y26339D03*
X439554Y30429D03*
X439302Y34040D03*
X458972Y49634D03*
X462625Y49881D03*
X467300Y20000D03*
X450454Y38147D03*
X448520Y49979D03*
X430800Y22200D03*
X433600Y19900D03*
X428001Y25269D03*
X433400Y63373D03*
X438600Y91033D03*
X419662Y71426D03*
X423340Y71621D03*
X469901Y94047D03*
X415211Y71263D03*
X461736Y111300D03*
X442800Y90934D03*
X496700Y32100D03*
X482693Y42200D03*
X478500Y19775D03*
X490050Y45900D03*
X506970Y18693D03*
X502830D03*
X477400Y69300D03*
X512806Y49494D03*
X473151Y50052D03*
X521200Y57600D03*
X496035Y46435D03*
X503814Y56676D03*
X515500Y57900D03*
X486568Y38006D03*
X486114Y41700D03*
X496430Y22890D03*
X491270Y18877D03*
X485674Y32924D03*
X524950Y16120D03*
X473172Y95508D03*
X479147Y102165D03*
X490100Y111300D03*
X486400Y74700D03*
X481800Y71200D03*
X513909Y85849D03*
X510408Y85779D03*
X559200Y36265D03*
X552540Y64530D03*
X599422Y51662D03*
X568430Y50010D03*
X596489Y14110D03*
X559600Y47600D03*
X575550Y42800D03*
X601311Y13521D03*
X569300Y66274D03*
X545200Y69000D03*
X596300Y66950D03*
X549550Y61900D03*
X597950Y58950D03*
X564500Y64100D03*
X573600Y49750D03*
X577100Y78600D03*
X545300Y75600D03*
X568000Y70000D03*
X584550Y80750D03*
X559900Y88400D03*
X563268Y88872D03*
X540179Y111036D03*
X539346Y114333D03*
X578900Y82500D03*
X551500Y82400D03*
X599682Y103715D03*
X547100Y79900D03*
X578400Y74500D03*
X562160Y178600D03*
X582219Y386612D03*
X599998Y391270D03*
X598964Y354128D03*
X596077Y369579D03*
X602075Y339970D03*
X586155Y393023D03*
X593064Y400910D03*
X593229Y397308D03*
X666535Y26149D03*
X665800Y7550D03*
X666400Y22200D03*
X638470Y164470D03*
X634910Y169360D03*
X644100Y199850D03*
X630000Y169600D03*
X629500Y187500D03*
X619980Y197550D03*
X630800Y147600D03*
X634800Y147700D03*
X666700Y205600D03*
X629400Y217300D03*
X644100Y203350D03*
X634450Y252100D03*
X631550Y249850D03*
X625926Y247530D03*
X627200Y253550D03*
X625250Y264250D03*
X625550Y244150D03*
Y240750D03*
X645516Y225334D03*
X620750Y258050D03*
X642547Y226992D03*
X632958Y231000D03*
X633109Y234397D03*
X632900Y238000D03*
X628300Y230550D03*
X625700Y235750D03*
X640141Y259859D03*
X640400Y217600D03*
X636491Y217592D03*
X633092Y217496D03*
X659500Y205300D03*
X665500Y201900D03*
X662900Y205300D03*
X645400Y264050D03*
X620160Y203500D03*
X648700Y292900D03*
X660700Y292200D03*
X634830Y292095D03*
X638453Y291949D03*
X633400Y274600D03*
X657500Y281500D03*
X652850Y269600D03*
X642300Y276450D03*
X649000Y273500D03*
X652100Y279300D03*
X648000Y281300D03*
X638603Y296320D03*
X642003Y296249D03*
X645403Y296229D03*
X631069Y292512D03*
X654670Y391494D03*
X616428Y379533D03*
X626772Y371336D03*
X612300Y344300D03*
X613480Y333710D03*
X629900Y339300D03*
X610300Y354800D03*
X654600Y367600D03*
X639318Y354003D03*
X643082Y353941D03*
X629239Y387969D03*
X620100Y384100D03*
X659300Y373100D03*
X637000Y373856D03*
X632220Y389694D03*
X607800Y382362D03*
X607100Y351200D03*
X638360Y383805D03*
X642270Y383869D03*
X605400Y393400D03*
X618600Y364375D03*
X609240Y370337D03*
X616900Y343000D03*
X615150Y364200D03*
X640968Y370425D03*
X606626Y354723D03*
X637353Y379591D03*
X657900Y443200D03*
X655100Y436900D03*
X636963Y405999D03*
X632180Y397968D03*
X654300Y504100D03*
X613000Y463000D03*
X632800Y561600D03*
X620160Y544793D03*
X653600Y540300D03*
X635970Y557600D03*
X638660Y568043D03*
X616160Y542700D03*
X614000Y561250D03*
X606600Y551100D03*
X722150Y174300D03*
X727150Y184550D03*
X722150D03*
X711150Y174300D03*
X716650Y184550D03*
X711150D03*
X705650D03*
X677770Y196410D03*
X704579Y258164D03*
X721261Y240551D03*
X721260Y234252D03*
X730710Y256302D03*
X733858Y256299D03*
Y253149D03*
X730710Y253152D03*
X733859Y234253D03*
Y237403D03*
X730710D03*
Y234254D03*
X733858Y243700D03*
Y246849D03*
Y249999D03*
Y265747D03*
X730710Y240553D03*
Y243702D03*
Y246852D03*
Y250002D03*
Y265750D03*
X721295Y221651D03*
X718089Y243684D03*
X721260Y253150D03*
Y259449D03*
Y265748D03*
X721261Y246851D03*
X733859Y240552D03*
X727559Y259449D03*
Y265748D03*
Y253150D03*
Y240551D03*
X727560Y246851D03*
X727559Y221654D03*
Y234252D03*
X727594Y227950D03*
X696600Y241500D03*
X701500Y250564D03*
X691600Y207600D03*
X718121Y256326D03*
X718089Y246834D03*
X718098Y259423D03*
X718072Y265748D03*
X718089Y249984D03*
X718129Y253144D03*
X693800Y264300D03*
X725466Y200819D03*
X707923Y219765D03*
X708900Y214500D03*
X718111Y224802D03*
X706500Y212150D03*
X709615Y223228D03*
X718111Y231101D03*
X696300Y215750D03*
X702900Y212350D03*
X707679Y233664D03*
X718111Y227952D03*
X722322Y200935D03*
X704279Y226664D03*
X705529Y231064D03*
X705779Y236764D03*
X706079Y240664D03*
X710716Y235827D03*
X714945Y234230D03*
X726988Y204312D03*
X718123Y201101D03*
X710079Y203664D03*
X718895Y207125D03*
X705364Y205864D03*
X713168Y207689D03*
X718111Y221653D03*
X733859Y215355D03*
X718110Y234252D03*
X709679Y239164D03*
X727560Y215355D03*
X716116Y207469D03*
X718111Y237401D03*
X709079Y229564D03*
X703979Y219995D03*
X718111Y240550D03*
X711812Y243700D03*
X714961D03*
X730709Y215355D03*
X724410D03*
X732264Y204312D03*
X703320Y203900D03*
X733859Y212206D03*
X729800Y208400D03*
X724410Y281496D03*
X730710D03*
X733859D03*
Y275198D03*
X730710Y272048D03*
X733858Y268897D03*
X721820Y315750D03*
X730710Y268899D03*
X721260Y275196D03*
Y272047D03*
X733859Y278346D03*
X677300Y314900D03*
X681200D03*
X684400Y313400D03*
X688000Y313200D03*
X694675Y323900D03*
X730708Y290944D03*
X724409D03*
X727559Y272047D03*
Y278346D03*
X708100Y331410D03*
X718340Y315800D03*
X706796Y295829D03*
X726895Y309117D03*
X711799Y304234D03*
X713339Y306954D03*
X724063Y306305D03*
X698039Y285854D03*
X707834Y293060D03*
X707079Y286964D03*
X704079Y300964D03*
X719200Y307400D03*
X705579Y298464D03*
X695508Y288964D03*
X710679Y267894D03*
X721230Y284653D03*
X718099Y290964D03*
X710329Y285214D03*
X718117Y281465D03*
X718080Y284653D03*
X701708Y292364D03*
X706277Y279162D03*
X718072Y278346D03*
X708409Y276771D03*
X733892Y297246D03*
X730708Y297243D03*
X714619Y303884D03*
X692750Y293200D03*
X718109Y272034D03*
X694307Y283485D03*
X722468Y308964D03*
X727558Y297243D03*
X733859Y272048D03*
X690579Y299964D03*
X675555Y318736D03*
X672350Y317600D03*
X724409Y297243D03*
X700323Y283078D03*
X716300Y331340D03*
X733859Y284646D03*
X695300Y306700D03*
X718099Y287814D03*
X718137Y275186D03*
X702939Y281484D03*
X718109Y268934D03*
X714949Y287814D03*
X731400Y362700D03*
X727000Y353000D03*
X712417Y352800D03*
X718300Y362900D03*
X708300Y445800D03*
X709006Y410206D03*
X721504Y402321D03*
X699900Y453600D03*
X691813Y407210D03*
X691874Y410741D03*
X691873Y403800D03*
X690550Y453850D03*
X690300Y460200D03*
X720900Y412900D03*
X728874Y470860D03*
X725366Y470722D03*
X677275Y485625D03*
X683583Y485841D03*
X702824Y476476D03*
X682400Y463400D03*
X696800Y476400D03*
X689100Y507900D03*
X730600Y493100D03*
X716078Y492334D03*
X672500Y507100D03*
X696000Y508400D03*
X715391Y479109D03*
X703440Y548820D03*
X710459Y554134D03*
X719626Y590829D03*
X725000Y576100D03*
X714800Y567956D03*
X710000Y549100D03*
X710100Y545600D03*
X705176Y593429D03*
X717450Y551554D03*
X705676Y562429D03*
X722300Y608200D03*
X708600Y608500D03*
X702515Y597064D03*
X693900Y597800D03*
X703800Y608400D03*
X712708Y603038D03*
X722122Y611840D03*
X777550Y62350D03*
X795832Y66750D03*
X787360Y35650D03*
X776300Y47600D03*
X769812Y53660D03*
X756431Y54010D03*
X736803Y52087D03*
X779400Y54750D03*
X746500Y47200D03*
X780815Y47062D03*
X776600Y35250D03*
X762765Y42200D03*
X781250Y101750D03*
X779594Y126865D03*
X762000Y113000D03*
X763825Y89975D03*
X776500Y82700D03*
X750500Y118500D03*
X750600Y114200D03*
X769500Y91000D03*
X792600Y101300D03*
X772800Y107550D03*
X776850Y115050D03*
X749600Y199300D03*
X749400Y195600D03*
X753800Y181500D03*
X753400Y185400D03*
X741300Y185700D03*
X738160Y199480D03*
X765900Y191900D03*
X768579Y203964D03*
X764900Y207200D03*
X768505Y243702D03*
X784277Y243713D03*
X784253Y227953D03*
Y231103D03*
X752756Y234253D03*
Y231103D03*
Y224804D03*
Y227954D03*
X749606Y231103D03*
Y234253D03*
Y227954D03*
Y224804D03*
X737008Y256299D03*
X740158D03*
Y253149D03*
X737008D03*
X771655Y237402D03*
X765353D03*
X737009Y237400D03*
X737008Y243700D03*
Y246849D03*
Y249999D03*
Y265747D03*
X740158Y246849D03*
Y265747D03*
X740122Y243700D03*
X740158Y249999D03*
X752756Y221654D03*
X737008D03*
X771654Y253150D03*
X777954Y237402D03*
Y227953D03*
Y231103D03*
X765355Y265749D03*
X771654Y259449D03*
Y265749D03*
X793701Y221654D03*
X781103Y227954D03*
X784277Y246863D03*
X784267Y259426D03*
X746457Y224804D03*
X755906D03*
X737009Y227953D03*
Y234253D03*
Y231103D03*
X774804Y221655D03*
Y224804D03*
Y227954D03*
X746457D03*
X755906D03*
X746457Y231103D03*
X755906D03*
X746457Y234253D03*
X755906D03*
X759056Y253150D03*
X765355Y234253D03*
X765354Y231102D03*
X765355Y227953D03*
X765354Y246850D03*
X784277Y253162D03*
X740132Y240562D03*
X759055Y221654D03*
X765355Y224804D03*
X771654Y215355D03*
Y209056D03*
Y212205D03*
X746457Y240552D03*
X752757D03*
X759056D03*
X746421Y253149D03*
X749455Y202200D03*
X765354Y221654D03*
X743307D03*
X762205Y215355D03*
X781103Y237402D03*
Y231103D03*
X787402Y221654D03*
X787401Y215354D03*
X746457Y246850D03*
X752720Y253149D03*
X752757Y246851D03*
X765355Y253150D03*
X759056Y246851D03*
X746433Y265761D03*
X746457Y259449D03*
X752757D03*
Y265749D03*
X765355Y259449D03*
X759056Y265749D03*
X759031Y259461D03*
X777976Y265761D03*
X784267Y256276D03*
X793701Y231103D03*
X793672Y243709D03*
X799991Y249972D03*
X799972Y262588D03*
X796822D03*
Y256289D03*
X790551Y259486D03*
X790538Y265723D03*
X793701Y237402D03*
X777976Y259461D03*
X781102Y221654D03*
X749606D03*
X762205Y212205D03*
X761600Y207300D03*
X787402Y240552D03*
Y243701D03*
X793700Y256262D03*
X752759Y218499D03*
X755909Y218514D03*
X790550Y253150D03*
X799972Y256309D03*
X781080Y265763D03*
X784258Y262618D03*
X777967Y262576D03*
X790523Y256289D03*
X800021Y243717D03*
X795593Y206063D03*
X777953Y256300D03*
X781300Y207800D03*
X774803Y265749D03*
X737009Y240552D03*
X746457Y215355D03*
X737029Y215337D03*
X743279Y215364D03*
X740158Y215355D03*
X743279Y212196D03*
X741294Y208274D03*
X743008Y206059D03*
X793701Y234254D03*
X781127Y246863D03*
X793672Y240560D03*
X796821Y246859D03*
X793701Y227954D03*
X793674Y265758D03*
X793699Y262634D03*
X768504Y215355D03*
X763963Y331837D03*
X766437Y329363D03*
X769266Y326534D03*
X748737Y330263D03*
X751566Y327434D03*
X762229Y290933D03*
X752756Y278346D03*
X759073Y287810D03*
X774826Y268910D03*
X737009Y281496D03*
X740159Y278345D03*
Y281496D03*
X759031Y275209D03*
X765356Y272048D03*
Y275197D03*
Y278347D03*
X740158Y275197D03*
Y272046D03*
X737008D03*
Y268897D03*
X740158D03*
X746457Y272047D03*
Y275197D03*
X752757D03*
X752731Y272060D03*
X762181D03*
X759031D03*
X762206Y275197D03*
Y278347D03*
X737009Y275196D03*
X790551Y284646D03*
X781100Y287800D03*
X787419Y278354D03*
X737007Y290944D03*
X749579Y297254D03*
X787402Y297243D03*
X781102Y297244D03*
X771654Y297243D03*
X759058Y300414D03*
X768503Y287794D03*
X774802D03*
X787400Y287795D03*
X749607Y275197D03*
X774789Y275174D03*
X784221Y284652D03*
X777915Y281496D03*
X762189Y281514D03*
X768489Y281474D03*
X777953Y275198D03*
Y278347D03*
X784290Y272047D03*
X743306Y290944D03*
X749606Y278346D03*
X749593Y284670D03*
X799999Y290944D03*
Y284645D03*
Y278345D03*
X799974Y272058D03*
X793701Y300393D03*
X790519Y272053D03*
X790550Y287795D03*
X749605Y290944D03*
X762204Y287794D03*
X781064Y272047D03*
X784243Y278318D03*
X780300Y309300D03*
X740157Y297243D03*
X737008Y297244D03*
X740158Y284646D03*
X744881Y309000D03*
X743306Y297243D03*
X790526Y300406D03*
X765369Y281474D03*
X771669D03*
X781120Y284665D03*
X759070Y281514D03*
X749816Y303716D03*
X777790Y304778D03*
X769768Y304464D03*
X759208Y304284D03*
X784252Y268885D03*
X796839Y290934D03*
X787438Y275197D03*
X796832Y272064D03*
X796875Y304331D03*
X796862Y281522D03*
X784249Y281464D03*
X787426Y272060D03*
X790551Y278384D03*
X743308Y284646D03*
X746457D03*
X737009D03*
X744400Y322800D03*
X746456Y297243D03*
X765353Y287794D03*
X771653D03*
X777952D03*
X784251D03*
X762225Y297227D03*
X755898Y287804D03*
X793700Y297243D03*
X796849D03*
X790545Y290959D03*
X793694D03*
X793703Y287797D03*
X796839Y287784D03*
X793675Y284637D03*
X793679Y281508D03*
X793675Y278357D03*
X796868Y278364D03*
X793737Y275196D03*
X793682Y272064D03*
X793683Y268879D03*
X796850Y268910D03*
X799534Y339466D03*
X760252Y353266D03*
X763081Y350437D03*
X765555Y347963D03*
X768384Y345134D03*
X761134Y334666D03*
X772352Y341266D03*
X775181Y338437D03*
X777655Y335963D03*
X780484Y333134D03*
X777434Y353566D03*
X780263Y350737D03*
X782737Y348263D03*
X785566Y345434D03*
X789334Y341766D03*
X792163Y338937D03*
X794637Y336463D03*
X797466Y333634D03*
X743434Y335566D03*
X746263Y332737D03*
X749534Y346566D03*
X752363Y343737D03*
X754837Y341263D03*
X757666Y338434D03*
X795026Y374556D03*
X799426Y374456D03*
X738465Y352935D03*
X790357Y377781D03*
X735300Y401957D03*
X774700Y483600D03*
X794700Y505200D03*
X747125Y483924D03*
X743726Y483813D03*
X755500Y492600D03*
X768500Y480000D03*
X740253Y483893D03*
X797323Y512162D03*
X782000Y505600D03*
X771184Y514916D03*
X745700Y498250D03*
X742300Y498200D03*
X759000Y482900D03*
X759169Y497414D03*
X750600Y497400D03*
X759200Y508000D03*
X777600Y512200D03*
X781700Y510900D03*
X736600Y500000D03*
X780750Y496750D03*
X781050Y492550D03*
X757099Y530082D03*
X763809Y537191D03*
X782709Y537691D03*
X753099Y530282D03*
X795922Y531500D03*
X747200Y611900D03*
X826925Y57425D03*
X802786Y57150D03*
X841300Y54200D03*
X818785Y50692D03*
X803000Y117100D03*
X813349Y73142D03*
X809349Y73197D03*
X821962Y189277D03*
X831504Y199129D03*
X843419Y261781D03*
X840591Y264609D03*
X837619Y255281D03*
X834791Y258109D03*
X831609Y261291D03*
X828781Y264119D03*
X836955Y245662D03*
X834127Y248490D03*
X830945Y251672D03*
X828117Y254500D03*
X832148Y204444D03*
X816079Y250464D03*
X802227Y208424D03*
X802246Y205826D03*
X807468Y234464D03*
X808923Y245979D03*
X806968Y253464D03*
X804600Y210800D03*
X808400D03*
X816900Y231700D03*
X803160Y259454D03*
X803150Y256336D03*
X807177Y261023D03*
X814262Y218950D03*
X810277Y243190D03*
X810688Y238944D03*
X803129Y240535D03*
X803158Y237414D03*
X806862Y243302D03*
X806918Y237804D03*
X826000Y233400D03*
X828000Y243100D03*
X854419Y307581D03*
X851591Y310409D03*
X848409Y313591D03*
X845581Y316419D03*
X858919Y292081D03*
X856091Y294909D03*
X852909Y298091D03*
X850081Y300919D03*
X852919Y286081D03*
X850091Y288909D03*
X846909Y292091D03*
X844081Y294919D03*
X849419Y267581D03*
X846591Y270409D03*
X843409Y273591D03*
X840581Y276419D03*
X847419Y280581D03*
X844591Y283409D03*
X841409Y286591D03*
X838581Y289419D03*
X837409Y267791D03*
X834581Y270619D03*
X807666Y331334D03*
X822817Y331022D03*
X825646Y328193D03*
X803300Y303700D03*
X810300Y326450D03*
X823250Y319350D03*
X814450Y306950D03*
X810079Y271264D03*
X809968Y290464D03*
X808400Y300900D03*
X812164Y279674D03*
X802363Y336637D03*
X804837Y334163D03*
X817514Y336325D03*
X820343Y333496D03*
X810946Y389734D03*
X811112Y393735D03*
X857581Y391433D03*
X817700Y385700D03*
X851100Y407500D03*
X861000Y410500D03*
X806400Y398700D03*
X810100Y404934D03*
X857000Y410600D03*
X850950Y489300D03*
X846000Y476100D03*
X849050Y481050D03*
X809384Y484984D03*
X800800Y526900D03*
X804584Y526584D03*
X829500Y481500D03*
X821050Y533350D03*
X813150Y533450D03*
X888551Y226649D03*
X882871Y243771D03*
X892449Y241249D03*
X886300Y221150D03*
X896969Y301500D03*
X883240Y301973D03*
X888668Y322100D03*
X886540Y388996D03*
X872750Y403400D03*
G54D21*
X65900Y671000D03*
X65700Y660900D03*
X70600Y665800D03*
X60700Y665900D03*
X70800Y660700D03*
X60800Y660900D03*
X70700Y671000D03*
X60600Y670900D03*
X65714Y665850D03*
X135019Y706095D03*
X130019D03*
X139916Y705822D03*
X130019Y724095D03*
X135019Y714845D03*
Y719095D03*
Y723595D03*
Y710595D03*
X130019Y720495D03*
Y716895D03*
Y713295D03*
Y709695D03*
X139916Y723822D03*
Y720222D03*
Y716622D03*
Y713022D03*
Y709422D03*
X306486Y643750D03*
X306286Y633650D03*
X311186Y638550D03*
X301286Y638650D03*
X311386Y633450D03*
X301386Y633650D03*
X311286Y643750D03*
X301186Y643650D03*
X306300Y638600D03*
X295634Y710070D03*
X290520Y715120D03*
X300620Y715220D03*
X290720Y705120D03*
X300720Y704920D03*
X290620Y710120D03*
X300520Y710020D03*
X295620Y705120D03*
X295820Y715220D03*
X371400Y606400D03*
X358900Y612800D03*
X358800Y606300D03*
X365300Y606500D03*
X371400Y612700D03*
X371300Y618800D03*
X365500Y619000D03*
X358900Y618800D03*
X365164Y612620D03*
X468000Y35400D03*
X464000Y35500D03*
X468000Y39500D03*
Y31500D03*
X472000Y35500D03*
X601500Y363600D03*
X700546Y577599D03*
X691796D03*
X691296Y572599D03*
X705696D03*
X696296Y577599D03*
X709296Y572599D03*
Y577599D03*
X702096Y572599D03*
X694896D03*
X698496D03*
X704796Y577599D03*
X709569Y582496D03*
X698769D03*
X695169D03*
X691569D03*
X702369D03*
X705969D03*
X810200Y494900D03*
X815100Y499800D03*
X805200Y499900D03*
X815300Y494700D03*
X805300Y494900D03*
X815200Y505000D03*
X805100Y504900D03*
X810214Y499850D03*
X810400Y505000D03*
G54D26*
X201801Y684252D03*
X225601D03*
G54D37*
X651575Y20039D03*
X608267D03*
X641732Y126811D03*
X624015D03*
X651575Y72441D03*
X608267D03*
X730315Y20039D03*
X687007D03*
X720472Y126811D03*
X702755D03*
X730315Y72441D03*
X687007D03*
G54D32*
X421653Y130709D03*
X428740Y125985D03*
X435827Y130709D03*
X442913Y125985D03*
X450000Y130709D03*
X457086Y125985D03*
X464173Y130709D03*
X471260Y125985D03*
X428740Y131496D03*
X442913D03*
X457086D03*
X471260D03*
X421653Y136221D03*
X435827D03*
X450000D03*
X464173D03*
X421653Y144882D03*
X428740Y140158D03*
X435827Y144882D03*
X442913Y140158D03*
X450000Y144882D03*
X457086Y140158D03*
X464173Y144882D03*
X471260Y140158D03*
X421653Y150394D03*
X428740Y145670D03*
X435827Y150394D03*
X442913Y145670D03*
X450000Y150394D03*
X457086Y145670D03*
X464173Y150394D03*
X471260Y145670D03*
X421653Y159055D03*
X428740Y154331D03*
X435827Y159055D03*
X442913Y154331D03*
X450000Y159055D03*
X457086Y154331D03*
X464173Y159055D03*
X471260Y154331D03*
X421653Y164567D03*
X428740Y159843D03*
X435827Y164567D03*
X442913Y159843D03*
X450000Y164567D03*
X457086Y159843D03*
X464173Y164567D03*
X471260Y159843D03*
X421653Y173229D03*
X428740Y168504D03*
X435827Y173229D03*
X442913Y168504D03*
X450000Y173229D03*
X457086Y168504D03*
X464173Y173229D03*
X471260Y168504D03*
X421653Y178740D03*
X428740Y174016D03*
X435827Y178740D03*
X442913Y174016D03*
X450000Y178740D03*
X457086Y174016D03*
X464173Y178740D03*
X471260Y174016D03*
X506693Y126378D03*
X520866D03*
X513779Y121654D03*
X527953D03*
X506693Y130709D03*
X513779Y125985D03*
X520866Y130709D03*
X527953Y125985D03*
X535039Y130709D03*
X513779Y131496D03*
X527953D03*
X506693Y183071D03*
X520866D03*
X506693Y136221D03*
X520866D03*
X535039D03*
X506693Y140551D03*
X513779Y135827D03*
X520866Y140551D03*
X527953Y135827D03*
X506693Y144882D03*
X513779Y140158D03*
X520866Y144882D03*
X527953Y140158D03*
X535039Y144882D03*
X506693Y150394D03*
X513779Y145670D03*
X520866Y150394D03*
X527953Y145670D03*
X535039Y150394D03*
X506693Y154725D03*
X513779Y150000D03*
X520866Y154725D03*
X527953Y150000D03*
X513779Y154331D03*
X520866Y159055D03*
X527953Y154331D03*
X535039Y159055D03*
X513779Y159843D03*
X520866Y164567D03*
X527953Y159843D03*
X535039Y164567D03*
X506693Y168898D03*
X513779Y164173D03*
X520866Y168898D03*
X527953Y164173D03*
X513779Y168504D03*
X520866Y173229D03*
X527953Y168504D03*
X535039Y173229D03*
X520866Y178740D03*
X527953Y174016D03*
X535039Y178740D03*
X542126Y125985D03*
X549212Y130709D03*
X556299Y125985D03*
X542126Y131496D03*
X556299D03*
X549212Y136221D03*
X542126Y140158D03*
X549212Y144882D03*
X556299Y140158D03*
X542126Y145670D03*
X549212Y150394D03*
X556299Y145670D03*
X542126Y154331D03*
X549212Y159055D03*
X556299Y154331D03*
X542126Y159843D03*
X549212Y164567D03*
X556299Y159843D03*
X542126Y168504D03*
X549212Y173229D03*
X556299Y168504D03*
X542126Y174016D03*
X549212Y178740D03*
X556299Y174016D03*
X638780Y69685D03*
X629921D03*
X621063D03*
X638780Y114567D03*
X635827Y120079D03*
X629921Y114567D03*
X626969Y120079D03*
X621063Y114567D03*
X618110Y120079D03*
X638780Y99606D03*
X635827Y105118D03*
X629921Y99606D03*
X621063D03*
X626969Y105118D03*
X618110D03*
X638780Y84646D03*
X635827Y90157D03*
X626969D03*
X629921Y84646D03*
X621063D03*
X618110Y90157D03*
X635827Y75197D03*
X626969D03*
X618110D03*
X717520Y69685D03*
X708661D03*
X699803D03*
X717520Y114567D03*
X714567Y120079D03*
X708661Y114567D03*
X705709Y120079D03*
X699803Y114567D03*
X696850Y120079D03*
X717520Y99606D03*
X714567Y105118D03*
X708661Y99606D03*
X699803D03*
X705709Y105118D03*
X696850D03*
X717520Y84646D03*
X714567Y90157D03*
X705709D03*
X708661Y84646D03*
X699803D03*
X696850Y90157D03*
X714567Y75197D03*
X705709D03*
X696850D03*
G54D30*
X305906Y388386D03*
G54D11*
X8500Y428279D03*
Y438279D03*
Y448279D03*
Y458279D03*
Y433279D03*
Y443279D03*
Y453279D03*
Y468279D03*
Y478279D03*
Y488279D03*
Y498279D03*
Y508279D03*
Y518279D03*
Y528279D03*
Y463279D03*
Y473279D03*
Y483279D03*
Y493279D03*
Y503279D03*
Y513279D03*
Y523279D03*
Y538279D03*
Y548279D03*
Y558279D03*
Y568279D03*
Y578279D03*
Y588279D03*
Y533279D03*
Y543279D03*
Y553279D03*
Y563279D03*
Y573279D03*
Y583279D03*
Y593279D03*
Y598279D03*
Y608279D03*
Y618279D03*
Y628279D03*
Y638279D03*
Y648279D03*
Y658279D03*
Y603279D03*
Y613279D03*
Y623279D03*
Y633279D03*
Y643279D03*
Y653279D03*
Y668279D03*
Y678279D03*
Y688279D03*
Y698279D03*
Y708279D03*
Y718279D03*
Y663279D03*
Y673279D03*
Y683279D03*
Y693279D03*
Y703279D03*
Y713279D03*
X75300Y674300D03*
X103600Y637800D03*
X103500Y645500D03*
Y650535D03*
X99600Y673500D03*
Y678500D03*
X86500Y703100D03*
X86600Y708300D03*
X96800Y662000D03*
X90200Y667100D03*
X85400D03*
X99600Y683500D03*
X134223Y691027D03*
X122435Y666782D03*
Y661982D03*
X144057Y755280D03*
X134057D03*
X124057D03*
X114057D03*
X109057D03*
X119057D03*
X129057D03*
X139057D03*
X101300Y744800D03*
X106100D03*
X110900D03*
X115700D03*
X120500D03*
X125300D03*
X208300Y704985D03*
X203500D03*
X198700D03*
X193900D03*
X155400Y717700D03*
X204057Y755280D03*
X194057D03*
X184057D03*
X174057D03*
X164057D03*
X154057D03*
X149057D03*
X159057D03*
X169057D03*
X179057D03*
X189057D03*
X199057D03*
X209057D03*
X222700Y704985D03*
X217900D03*
X213100D03*
X274057Y755280D03*
X264057D03*
X254057D03*
X244057D03*
X234057D03*
X224057D03*
X214057D03*
X219057D03*
X229057D03*
X239057D03*
X249057D03*
X259057D03*
X269057D03*
X315120Y8500D03*
X310120D03*
X305120D03*
X300120D03*
X296020Y9420D03*
Y14420D03*
Y19420D03*
Y24420D03*
Y29420D03*
X321382Y197574D03*
X335132Y195874D03*
X305862Y210014D03*
X321382Y202374D03*
X335132Y205974D03*
X335200Y640100D03*
X330400D03*
X335000Y615400D03*
X335300Y609800D03*
X335000Y621200D03*
X325600Y640100D03*
X330200Y709300D03*
X334650Y689700D03*
X335350Y684650D03*
X315520Y711720D03*
X325700Y711600D03*
X320320Y711720D03*
X304150Y674700D03*
X299350D03*
X334057Y755280D03*
X324057D03*
X314057D03*
X304057D03*
X294057D03*
X284057D03*
X279057D03*
X289057D03*
X299057D03*
X309057D03*
X319057D03*
X329057D03*
X526434Y43701D03*
X521634D03*
X520000Y63400D03*
X536794Y77373D03*
X531664Y78463D03*
X515915Y80576D03*
X520310Y76700D03*
X600700Y35700D03*
X595500Y35600D03*
X595700Y29800D03*
X600900Y29700D03*
X576610Y388416D03*
Y393416D03*
X576512Y369625D03*
Y364825D03*
X581312Y369625D03*
Y364825D03*
X576610Y398416D03*
Y403416D03*
Y408416D03*
Y413416D03*
Y418416D03*
Y423416D03*
Y428416D03*
Y433416D03*
Y438416D03*
Y443416D03*
Y448416D03*
Y453416D03*
Y458416D03*
Y463416D03*
Y468416D03*
Y473416D03*
Y478416D03*
Y483416D03*
Y488416D03*
Y493416D03*
X609200Y330400D03*
X658000Y431500D03*
Y409000D03*
Y414000D03*
Y426000D03*
Y420500D03*
X610000Y467500D03*
X609000Y473500D03*
Y478500D03*
Y483500D03*
X650400Y517600D03*
X656400Y517500D03*
X661500Y517600D03*
X708483Y311988D03*
X713283D03*
X714900Y453600D03*
X715200Y459600D03*
Y465000D03*
X670400Y565500D03*
Y560700D03*
Y555900D03*
Y551100D03*
Y546300D03*
Y541500D03*
Y536700D03*
X687015Y658100D03*
Y653300D03*
Y648500D03*
Y643700D03*
Y682100D03*
X673950Y686104D03*
Y691104D03*
Y696104D03*
Y701104D03*
Y706104D03*
X687015Y677300D03*
Y672500D03*
Y667700D03*
Y662900D03*
X780100Y8500D03*
X775100D03*
X770100D03*
X765100D03*
X760100D03*
X755100D03*
X750100D03*
X745100D03*
X787895D03*
X797895D03*
X792895D03*
X798359Y351659D03*
X795193Y355540D03*
X791786Y359001D03*
X735484Y429378D03*
Y434178D03*
Y462978D03*
Y458178D03*
Y453378D03*
Y448578D03*
Y443778D03*
Y438978D03*
X798000Y459300D03*
X740300Y427100D03*
Y431900D03*
X751100Y405400D03*
X755900D03*
X760700D03*
X765500D03*
X770300D03*
X775100D03*
X740300Y446300D03*
Y441500D03*
Y436700D03*
X790600Y458000D03*
X781000D03*
X785800D03*
X776200D03*
X789500Y405400D03*
X784700D03*
X779900D03*
X735484Y467778D03*
X807895Y8500D03*
X817895D03*
X827895D03*
X837895D03*
X847895D03*
X857895D03*
X862895D03*
X852895D03*
X842895D03*
X832895D03*
X822895D03*
X812895D03*
X802895D03*
X842600Y339400D03*
X841100Y332300D03*
X826993Y358840D03*
X821502Y358356D03*
X827145Y363638D03*
X821653Y363488D03*
X826900Y332500D03*
X825300Y339900D03*
X825100Y347300D03*
X828100Y352900D03*
X809792Y379122D03*
X814592D03*
X809792Y374322D03*
X814592D03*
X842900Y347200D03*
X840800Y352800D03*
X828000Y459300D03*
X823200D03*
X832800D03*
X818400D03*
X807600D03*
X802800D03*
X812400D03*
X864727Y398458D03*
X823500Y436500D03*
X830100Y501500D03*
X839700D03*
X834900D03*
X827000Y516000D03*
X832000D03*
Y521000D03*
X827000D03*
X843900Y464000D03*
X848700Y465200D03*
Y470600D03*
X867895Y8500D03*
X877895D03*
X887895D03*
X897895D03*
X907895D03*
X916697Y19698D03*
Y29698D03*
Y39698D03*
Y49698D03*
Y59698D03*
Y69698D03*
Y64698D03*
Y54698D03*
Y44698D03*
Y34698D03*
Y24698D03*
Y14698D03*
X912895Y8500D03*
X902895D03*
X892895D03*
X882895D03*
X872895D03*
X916697Y79698D03*
Y89698D03*
Y99698D03*
Y109698D03*
Y119698D03*
Y129698D03*
Y134698D03*
Y124698D03*
Y114698D03*
Y104698D03*
Y94698D03*
Y84698D03*
Y74698D03*
Y139698D03*
Y149698D03*
Y159698D03*
Y169698D03*
Y179698D03*
Y189698D03*
Y199698D03*
Y194698D03*
Y184698D03*
Y174698D03*
Y164698D03*
Y154698D03*
Y144698D03*
Y209698D03*
Y219698D03*
Y229698D03*
Y239698D03*
Y249698D03*
Y259698D03*
Y264698D03*
Y254698D03*
Y244698D03*
Y234698D03*
Y224698D03*
Y214698D03*
Y204698D03*
Y269698D03*
Y279698D03*
Y289698D03*
Y299698D03*
Y309698D03*
Y319698D03*
Y329698D03*
Y324698D03*
Y314698D03*
Y304698D03*
Y294698D03*
Y284698D03*
Y274698D03*
Y339698D03*
Y349698D03*
Y359698D03*
Y369698D03*
Y379698D03*
Y389698D03*
Y394698D03*
Y384698D03*
Y374698D03*
Y364698D03*
Y354698D03*
Y344698D03*
Y334698D03*
X881147Y394517D03*
X916697Y399698D03*
Y409698D03*
Y419698D03*
Y429698D03*
Y439698D03*
Y449698D03*
Y459698D03*
Y454698D03*
Y444698D03*
Y434698D03*
Y424698D03*
Y414698D03*
Y404698D03*
X874727Y398458D03*
X869727D03*
X880887Y399474D03*
X916697Y469698D03*
Y479698D03*
Y489698D03*
Y499698D03*
Y509698D03*
Y519698D03*
Y524698D03*
Y514698D03*
Y504698D03*
Y494698D03*
Y484698D03*
Y474698D03*
Y464698D03*
Y529698D03*
Y539698D03*
Y549698D03*
Y559698D03*
Y569698D03*
Y579698D03*
Y589698D03*
Y584698D03*
Y574698D03*
Y564698D03*
Y554698D03*
Y544698D03*
Y534698D03*
Y599698D03*
Y609698D03*
Y619698D03*
Y614698D03*
Y604698D03*
Y594698D03*
G54D35*
X564803Y24409D03*
X574803D03*
X584803D03*
X753780D03*
X763780D03*
X773780D03*
X801024D03*
X811024D03*
X821024D03*
G54D23*
X197243Y589764D03*
X203542Y592913D03*
X168898Y548819D03*
X172000Y577150D03*
X184645Y589764D03*
X175197D03*
X209842Y583464D03*
X187795Y570866D03*
X184646Y577165D03*
X187795D03*
X190945D03*
X190944Y574016D03*
X190945Y570866D03*
X187795Y574016D03*
X184646D03*
Y570866D03*
X187795Y564567D03*
X194094Y567716D03*
X190945D03*
X187795D03*
X184646D03*
X206692Y592913D03*
X184645Y539370D03*
X194094D03*
X203542Y545671D03*
X197243Y539371D03*
X206692Y555120D03*
X194093D03*
X184646D03*
X153149Y536221D03*
X165748Y558268D03*
X172048Y555120D03*
X156297Y558267D03*
X172048Y589764D03*
X168898D03*
Y561417D03*
Y570866D03*
X156299Y586614D03*
Y580315D03*
X159449Y567717D03*
X156299Y570866D03*
X197243Y592913D03*
X200393Y589764D03*
X187794Y586614D03*
X203542Y589764D03*
X187795Y592914D03*
X165748Y583464D03*
X209841Y574016D03*
X206692D03*
X165745Y564567D03*
X168895D03*
X159449Y561417D03*
X165748D03*
X172047D03*
X162598Y558268D03*
X168898D03*
X165748Y555118D03*
X159449D03*
X168898Y567717D03*
X159449Y570866D03*
X168898Y583464D03*
Y577165D03*
X159449Y586614D03*
X162598Y580315D03*
Y586614D03*
X165748D03*
X168898D03*
X159449Y577165D03*
X156299D03*
X168898Y580315D03*
X159449D03*
X162598Y577165D03*
X165748Y580315D03*
X162598Y583464D03*
X165748Y570866D03*
Y567717D03*
X162598D03*
X172047Y570866D03*
X162597Y555118D03*
X197243Y551970D03*
X194093D03*
X190945Y542519D03*
X172047Y545669D03*
Y551970D03*
X159449Y545671D03*
X162599Y545669D03*
X165749D03*
X184646Y548821D03*
Y545671D03*
X209842Y567717D03*
X184645Y542519D03*
X206692Y542521D03*
X209841Y577165D03*
X159449Y542521D03*
X156299Y545671D03*
X168898Y592913D03*
X181497Y545671D03*
X209842Y545669D03*
X165749Y548819D03*
X175197Y545671D03*
X162599Y542519D03*
X168898D03*
X156299Y542521D03*
X181496Y542520D03*
X159449Y548821D03*
X206692Y589763D03*
X172047Y548819D03*
X168898Y551969D03*
X162599Y548821D03*
X194093Y589764D03*
Y592913D03*
X162598Y561417D03*
X168898Y555119D03*
X181497Y548821D03*
X178346Y545670D03*
X206692Y586614D03*
X209842Y586613D03*
X209841Y592913D03*
X162595Y564567D03*
X162598Y570866D03*
X203542Y548821D03*
Y586614D03*
Y580315D03*
X178344Y577166D03*
X178346Y586615D03*
X181497Y586614D03*
X178347Y574018D03*
Y570868D03*
X190944Y586614D03*
X200394Y570866D03*
Y574016D03*
X203543Y561418D03*
Y564568D03*
X165748Y551968D03*
X159448D03*
X178346Y555119D03*
X178347Y564569D03*
X197245Y555118D03*
X190944D03*
X181497Y555120D03*
X209842Y558268D03*
X190944Y589764D03*
Y592913D03*
X197244Y586615D03*
X200393Y586614D03*
X194094Y542519D03*
X209842Y564567D03*
X200393Y548819D03*
X209842Y561417D03*
Y589763D03*
X206692Y580315D03*
X209841D03*
X200393Y545669D03*
X206692Y545671D03*
X200393Y592913D03*
X159448Y589764D03*
Y592913D03*
X162598Y589764D03*
X165748D03*
Y592913D03*
X165749Y542519D03*
X175197Y592913D03*
X172048D03*
X209842Y555119D03*
Y551969D03*
X181497Y592913D03*
X197244Y545669D03*
X194094Y548820D03*
X209842Y548819D03*
X175197Y548821D03*
X168898Y545669D03*
X156300Y539371D03*
X194094Y545669D03*
X197244Y542520D03*
X194094Y602362D03*
X206692Y596063D03*
X194093D03*
X203605Y605450D03*
X200393Y596063D03*
X187795Y602363D03*
X153149Y605513D03*
X190945Y599213D03*
X190944Y596063D03*
X187796Y599212D03*
X184645Y599213D03*
X159448Y596063D03*
X168898D03*
X203542Y602362D03*
Y599213D03*
X206692Y602362D03*
X203542Y596063D03*
X194094Y599213D03*
X162598Y596063D03*
X165748Y599213D03*
X168898D03*
X162598D03*
X159448D03*
X172048Y596063D03*
X178346Y596064D03*
X178347Y599213D03*
X181496Y596062D03*
X209841Y599212D03*
X206692Y599213D03*
X165748Y596063D03*
X175197D03*
Y599213D03*
X172048D03*
X219800Y445700D03*
X213874Y445226D03*
X216141Y580315D03*
X212992Y586614D03*
X216141Y577165D03*
X212991Y567718D03*
X216141Y583465D03*
Y564569D03*
X212992Y561417D03*
X216141Y567718D03*
X219293Y567717D03*
X212992Y580315D03*
X212991Y577165D03*
Y574016D03*
X216141D03*
Y561419D03*
X212991Y583465D03*
Y542519D03*
X212992Y589764D03*
Y555119D03*
Y558268D03*
X216142Y548820D03*
X216141Y555120D03*
Y558269D03*
X222441Y548820D03*
X219291D03*
X212992Y551969D03*
X216141Y551970D03*
X212992Y548819D03*
X216141Y589762D03*
X212993Y592912D03*
X212992Y564567D03*
Y545669D03*
X216142D03*
X222440Y605512D03*
X212992Y602363D03*
X212991Y599212D03*
X216141D03*
X762173Y294089D03*
X781088Y294094D03*
X771653Y294093D03*
X777952Y290944D03*
X777989Y294093D03*
X774802Y290944D03*
X774835Y294088D03*
X768503Y290944D03*
X768498Y294124D03*
X765353Y290944D03*
X765325Y294102D03*
X759054Y290944D03*
X759055Y294094D03*
X755905Y290944D03*
Y294093D03*
X787401Y290944D03*
X787408Y294074D03*
X784251Y290944D03*
X784258Y294064D03*
G54D31*
X346457Y66850D03*
Y57007D03*
X353543Y70787D03*
Y62913D03*
Y55039D03*
X346457Y74724D03*
Y84567D03*
X353543Y86535D03*
Y78661D03*
G54D29*
X305906Y182874D03*
G54D12*
X80708Y44292D03*
X61024Y34449D03*
X33464D03*
X56102Y24606D03*
X38386D03*
X108268Y44292D03*
X103346Y34449D03*
X85630D03*
X590300Y574400D03*
X600300D03*
X610300D03*
G54D19*
X67853Y577015D03*
X91700Y744800D03*
X96500D03*
X628160Y569095D03*
X619400Y570451D03*
X706700Y413900D03*
X710200Y417400D03*
Y422900D03*
Y427900D03*
X698700Y417600D03*
Y423100D03*
Y428100D03*
X771653Y246887D03*
G54D10*
X8500Y18279D03*
Y28279D03*
Y38279D03*
Y48279D03*
Y58279D03*
Y68279D03*
X13721Y8500D03*
X8500Y13279D03*
Y23279D03*
Y33279D03*
Y43279D03*
Y53279D03*
Y63279D03*
Y78279D03*
Y88279D03*
Y98279D03*
Y108279D03*
Y118279D03*
Y128279D03*
Y73279D03*
Y83279D03*
Y93279D03*
Y103279D03*
Y113279D03*
Y123279D03*
Y133279D03*
Y138279D03*
Y148279D03*
Y158279D03*
Y168279D03*
Y178279D03*
Y188279D03*
Y198279D03*
Y143279D03*
Y153279D03*
Y163279D03*
Y173279D03*
Y183279D03*
Y193279D03*
Y208279D03*
Y218279D03*
Y228279D03*
Y238279D03*
Y248279D03*
Y258279D03*
Y203279D03*
Y213279D03*
Y223279D03*
Y233279D03*
Y243279D03*
Y253279D03*
Y263279D03*
Y268279D03*
Y278279D03*
Y288279D03*
Y298279D03*
Y308279D03*
Y318279D03*
Y328279D03*
Y273279D03*
Y283279D03*
Y293279D03*
Y303279D03*
Y313279D03*
Y323279D03*
Y338279D03*
Y348279D03*
Y358279D03*
Y368279D03*
Y378279D03*
Y388279D03*
Y333279D03*
Y343279D03*
Y353279D03*
Y363279D03*
Y373279D03*
Y383279D03*
Y393279D03*
Y398279D03*
Y408279D03*
Y418279D03*
Y403279D03*
Y413279D03*
Y423279D03*
X8892Y723187D03*
X11090Y727806D03*
X13500Y732400D03*
X78721Y8500D03*
X68721D03*
X58721D03*
X48721D03*
X38721D03*
X28721D03*
X18721D03*
X73721D03*
X53721D03*
X43721D03*
X33721D03*
X23721D03*
X77780Y61790D03*
X73760Y67930D03*
X56960Y58900D03*
X54050Y63260D03*
X43510Y57810D03*
X29890Y54070D03*
X49460Y63690D03*
X68730Y67930D03*
X63721Y8500D03*
X53524Y521269D03*
Y526995D03*
X75405Y521695D03*
X69778D03*
X64151D03*
X52408Y543876D03*
X64701Y542366D03*
X52603Y549526D03*
X52485Y555153D03*
X53300Y560879D03*
X63456Y555041D03*
X64701Y567566D03*
Y561266D03*
X53524Y532622D03*
X52613Y538242D03*
X75534Y625175D03*
X75300Y679300D03*
X47150Y665500D03*
X78370Y724300D03*
Y719500D03*
X28100Y755600D03*
X33100D03*
X69057Y755280D03*
X74057D03*
X20300Y746200D03*
X15800Y736900D03*
X18100Y741500D03*
X22600Y750800D03*
X79057Y755280D03*
X108721Y8500D03*
X98721D03*
X88721D03*
X112197Y65406D03*
Y60406D03*
Y55406D03*
X103721Y8500D03*
X93721D03*
X83721D03*
X84610Y64470D03*
X98770Y60860D03*
X112197Y75406D03*
Y85406D03*
Y95406D03*
Y105406D03*
Y115406D03*
Y120406D03*
Y110406D03*
Y100406D03*
Y90406D03*
Y80406D03*
Y70406D03*
Y145406D03*
Y195406D03*
Y185406D03*
Y175406D03*
Y165406D03*
Y155406D03*
Y200406D03*
Y190406D03*
Y180406D03*
Y170406D03*
Y160406D03*
Y150406D03*
Y265406D03*
Y255406D03*
Y245406D03*
Y235406D03*
Y225406D03*
Y215406D03*
Y205406D03*
Y260406D03*
Y250406D03*
Y240406D03*
Y230406D03*
Y220406D03*
Y210406D03*
Y325406D03*
Y315406D03*
Y305406D03*
Y295406D03*
Y285406D03*
Y275406D03*
Y330406D03*
Y320406D03*
Y310406D03*
Y300406D03*
Y290406D03*
Y280406D03*
Y270406D03*
Y390406D03*
Y380406D03*
Y370406D03*
Y360406D03*
Y350406D03*
Y395406D03*
Y385406D03*
Y375406D03*
Y365406D03*
Y355406D03*
Y345406D03*
Y335406D03*
Y340406D03*
Y420406D03*
Y410406D03*
Y400406D03*
Y425406D03*
Y415406D03*
Y405406D03*
X102250Y455000D03*
X117200Y495200D03*
X141980Y508590D03*
X97637Y492891D03*
X92286Y521695D03*
X81032D03*
X86659D03*
X97913D03*
X93051Y587466D03*
X83600Y567565D03*
X93049Y573864D03*
X93048Y580164D03*
X94720Y557158D03*
X118500Y638100D03*
X140700Y657700D03*
X130800Y656100D03*
X80334Y625175D03*
X81300Y675100D03*
Y680100D03*
X107100Y679600D03*
X83170Y724300D03*
Y719500D03*
X87683Y698924D03*
X104057Y755280D03*
X94057D03*
X84057D03*
X89057D03*
X99057D03*
X208370Y491570D03*
X170838Y481762D03*
X146300Y502600D03*
X146112Y509412D03*
X158100Y493000D03*
X158400Y513600D03*
X155001Y513707D03*
X182874Y513591D03*
X178869Y513593D03*
X166600Y513600D03*
X170700D03*
X146293Y464338D03*
X146193Y476938D03*
X146293Y472738D03*
X175100Y529100D03*
X191370Y608190D03*
X208700Y625149D03*
X200879Y614739D03*
X145900Y641300D03*
X164800Y640200D03*
X173000Y640400D03*
X193610Y640040D03*
X189500Y639700D03*
X206700Y695400D03*
X272000Y461800D03*
X268350Y461950D03*
X275700Y490300D03*
X244900Y527300D03*
X228150Y525750D03*
X275400Y470300D03*
X245743Y546963D03*
X270021Y549394D03*
X257000Y548400D03*
X263216Y554697D03*
X254530Y564300D03*
X251446Y553754D03*
X254500Y579500D03*
X273500Y567400D03*
X254300Y586500D03*
X273400Y590902D03*
X231434Y562844D03*
X234300Y582300D03*
X231200Y576800D03*
X231000Y571900D03*
X257300Y537500D03*
X214900Y529400D03*
X255570Y616631D03*
X258962Y616384D03*
X236000Y647400D03*
X225900Y630700D03*
X231500Y659100D03*
X228149Y600094D03*
X242710Y604620D03*
X255050Y675750D03*
X249500Y719500D03*
Y724300D03*
X254800Y689400D03*
X269200Y699600D03*
X258423Y711343D03*
X268520Y719420D03*
X270900Y667200D03*
X254648Y745463D03*
X249500Y729100D03*
Y733900D03*
Y738700D03*
X296282Y189224D03*
Y184424D03*
X301082D03*
Y189224D03*
X334882Y215874D03*
Y220874D03*
X335000Y226992D03*
X334000Y382700D03*
X325136Y519316D03*
X333922Y527323D03*
X340961Y511600D03*
X298335Y521458D03*
X304800Y512800D03*
X325774Y547428D03*
X331700Y587896D03*
X303520Y550085D03*
X296835Y591015D03*
X280646Y557150D03*
X303500Y582200D03*
X333847Y531105D03*
X286195Y530579D03*
X322586Y653754D03*
X317786D03*
X312986D03*
X308186D03*
X278443Y648857D03*
X284495Y613130D03*
X286700Y622190D03*
X321800Y678500D03*
X305500Y721000D03*
X310500D03*
X281000Y678000D03*
X304400Y665100D03*
X316465Y716063D03*
X339057Y755280D03*
X291700Y737000D03*
X305500Y726000D03*
X310500D03*
X361792Y243154D03*
X372888Y208022D03*
X359882Y203458D03*
X345582Y380874D03*
X357450Y491450D03*
X364500Y525260D03*
X369300Y508700D03*
X344400Y505400D03*
X383000Y577000D03*
X386305Y581647D03*
X362700Y551200D03*
X361279Y581647D03*
X362100Y574700D03*
X349000Y581360D03*
X379050Y539931D03*
X341740Y535800D03*
X348000Y612661D03*
X352720Y600970D03*
X367133Y596067D03*
X382380Y612277D03*
X352400Y626102D03*
X372408Y629626D03*
X381638Y755280D03*
X384809Y752321D03*
X387045Y747849D03*
X389281Y743376D03*
X391517Y738904D03*
X393753Y734432D03*
X395989Y729960D03*
X398225Y725488D03*
X344057Y755280D03*
X521634Y38901D03*
Y34101D03*
X516834Y38901D03*
Y34101D03*
Y43701D03*
X515200Y66440D03*
X520585Y68348D03*
X508668Y79607D03*
X503550Y79500D03*
X511100Y75060D03*
X506100D03*
X511100Y70060D03*
X525200Y71440D03*
X516628Y71806D03*
X576610Y498416D03*
Y503416D03*
Y508416D03*
Y513416D03*
Y518416D03*
Y523416D03*
Y528416D03*
Y533416D03*
Y538416D03*
Y543416D03*
Y548416D03*
Y553416D03*
Y558416D03*
Y563416D03*
Y568416D03*
Y573416D03*
Y578416D03*
Y583416D03*
Y588416D03*
Y593416D03*
Y598416D03*
Y603416D03*
Y608416D03*
Y613416D03*
Y618416D03*
Y623416D03*
Y628416D03*
Y633416D03*
Y638416D03*
Y643416D03*
Y648416D03*
Y653416D03*
Y658416D03*
Y663416D03*
Y668416D03*
Y673416D03*
Y678416D03*
Y683416D03*
Y688416D03*
Y693416D03*
Y698416D03*
Y703416D03*
Y708416D03*
Y713416D03*
Y718416D03*
X577063Y723309D03*
X579299Y727781D03*
X581535Y732253D03*
X583771Y736725D03*
X586007Y741198D03*
X588243Y745670D03*
X590479Y750142D03*
X592715Y754614D03*
X641732Y117323D03*
X632873D03*
X624015D03*
X641732Y102362D03*
X632873D03*
X624015D03*
X641732Y87402D03*
X632873D03*
X624015D03*
X641732Y72441D03*
X632873D03*
X624015D03*
X634000Y187500D03*
X656700Y305607D03*
X664600Y306100D03*
X648700Y303600D03*
X652500Y305707D03*
X608600Y362600D03*
X642700Y454400D03*
X642500Y449100D03*
X642600Y459500D03*
X645200Y521900D03*
X621600Y486619D03*
X626958Y486419D03*
X642500Y464700D03*
X629500Y482500D03*
Y477000D03*
Y471500D03*
X635000Y482500D03*
Y476500D03*
Y471000D03*
X666216Y470684D03*
X629200Y536040D03*
X629080Y539920D03*
X625500Y536100D03*
X615500Y529800D03*
X616710Y534500D03*
X610200Y555400D03*
X625300Y539900D03*
X657000Y555000D03*
X662000D03*
X661887Y560010D03*
X656887D03*
X645300Y655200D03*
Y650400D03*
Y645600D03*
Y640800D03*
X655000Y705000D03*
Y700200D03*
Y695400D03*
Y690600D03*
X645300Y684000D03*
Y679200D03*
Y674400D03*
Y669600D03*
Y664800D03*
Y660000D03*
X655000Y685800D03*
X659722Y755280D03*
X649722D03*
X639722D03*
X634722D03*
X644722D03*
X654722D03*
X664722D03*
X720472Y117323D03*
X711613D03*
X702755D03*
X720472Y102362D03*
X711613D03*
X702755D03*
X720472Y87402D03*
X711613D03*
X702755D03*
X720472Y72441D03*
X711613D03*
X702755D03*
X730550Y179050D03*
X732000Y185900D03*
X716650Y174400D03*
X674300Y198900D03*
X704579Y261964D03*
X682030Y253630D03*
X706100Y250000D03*
X690600Y230700D03*
X691243Y211743D03*
X692600Y201300D03*
X677800Y215900D03*
X723900Y326350D03*
X718940Y326270D03*
X712410Y331320D03*
X702250Y329650D03*
X730300Y314900D03*
X669950Y310950D03*
X681800Y287950D03*
X722500Y353000D03*
X718000D03*
X713500Y362900D03*
X729900Y393200D03*
X676000Y431000D03*
X671000D03*
Y421000D03*
X676000D03*
X671000Y426000D03*
X676000D03*
X689500Y518500D03*
Y524000D03*
X694738Y523940D03*
X694690Y519034D03*
X697200Y529200D03*
X723369Y599835D03*
X729722Y755280D03*
X719722D03*
X709722D03*
X699722D03*
X689722D03*
X679722D03*
X669722D03*
X674722D03*
X684722D03*
X694722D03*
X704722D03*
X714722D03*
X724722D03*
X734722D03*
X761900Y81700D03*
X772700Y113000D03*
X794650Y86050D03*
X769710Y125150D03*
X766110Y125270D03*
X793957Y113436D03*
X761950Y126450D03*
X773200Y97600D03*
X754000Y172700D03*
X749900Y185200D03*
X786343Y179959D03*
X745700Y185900D03*
X754000Y177500D03*
X769100Y187800D03*
X786388Y183429D03*
X772810Y179901D03*
X772700Y183300D03*
X737000Y185900D03*
X750000Y427100D03*
X754800D03*
X783800Y436000D03*
X779000D03*
X793400D03*
X788600D03*
X788400Y427100D03*
X783600D03*
X778800D03*
X774200Y436000D03*
X774000Y427100D03*
X769200D03*
X764400D03*
X759600D03*
X799722Y755280D03*
X789722D03*
X779722D03*
X769722D03*
X759722D03*
X749722D03*
X739722D03*
X744722D03*
X754722D03*
X764722D03*
X774722D03*
X784722D03*
X794722D03*
X801385Y183067D03*
X801340Y179597D03*
X811600Y317300D03*
X804300Y436500D03*
X813900D03*
X809100D03*
X818700D03*
X849722Y755280D03*
X839722D03*
X829722D03*
X819722D03*
X809722D03*
X804722D03*
X814722D03*
X824722D03*
X834722D03*
X844722D03*
X854722D03*
X916697Y629698D03*
Y639698D03*
Y649698D03*
Y659698D03*
Y654698D03*
Y644698D03*
Y634698D03*
Y624698D03*
Y669698D03*
Y679698D03*
Y689698D03*
Y699698D03*
Y709698D03*
Y719698D03*
Y714698D03*
Y704698D03*
Y694698D03*
Y684698D03*
Y674698D03*
Y664698D03*
X914700Y726100D03*
X912436Y730603D03*
X910200Y735300D03*
X907564Y739747D03*
X905500Y744400D03*
X903192Y748791D03*
X900800Y753700D03*
X894722Y755280D03*
G54D24*
X200395Y555120D03*
G54D34*
X488838Y164744D03*
G54D13*
X18700Y54650D03*
X209189Y37075D03*
Y383483D03*
X489331Y245605D03*
Y698924D03*
X901000Y21400D03*
X902500Y676000D03*
G54D33*
X488838Y137225D03*
G54D16*
X89764Y238386D03*
X309252Y413583D03*
G54D25*
X163189Y669291D03*
G54D36*
X629921Y57874D03*
X708661D03*
G54D38*
X652756Y180000D03*
X865353Y332598D03*
G54D28*
X339331Y91929D03*
X360669Y49803D03*
G54D22*
X90157Y413583D03*
X309055Y157677D03*
G54D15*
X70865Y98425D03*
Y472440D03*
X314960D03*
X405511Y39370D03*
X364173Y740157D03*
X612204Y433070D03*
Y740157D03*
X875984Y433070D03*
Y740157D03*
G54D20*
X49213D03*
X875985Y59055D03*
G54D17*
X67853Y570715D03*
Y561266D03*
X89899Y567565D03*
Y561265D03*
X86750D03*
X92600Y535623D03*
X181497Y551970D03*
Y589764D03*
X187795Y555120D03*
X206692Y564569D03*
Y561419D03*
Y558269D03*
Y567718D03*
X203543Y574017D03*
X206692Y583465D03*
X194093Y586614D03*
X178347Y551970D03*
X175197D03*
X178347Y589764D03*
X172048Y564569D03*
X172047Y567717D03*
X175298Y577266D03*
X209841Y596063D03*
X216141Y586614D03*
G54D18*
X74152Y583312D03*
X64703Y586463D03*
X105920Y477098D03*
X186602Y459767D03*
X183100Y499800D03*
X174900D03*
X172370Y463798D03*
X187000Y468000D03*
X186600Y477700D03*
X175197Y558268D03*
X421653Y126378D03*
X435827D03*
X450000D03*
X464173D03*
X428740Y121654D03*
X442913D03*
X457086D03*
X471260D03*
X421653Y183071D03*
X435827D03*
X450000D03*
X464173D03*
X421653Y140551D03*
X428740Y135827D03*
X435827Y140551D03*
X442913Y135827D03*
X450000Y140551D03*
X457086Y135827D03*
X464173Y140551D03*
X471260Y135827D03*
X421653Y154725D03*
X428740Y150000D03*
X435827Y154725D03*
X442913Y150000D03*
X450000Y154725D03*
X457086Y150000D03*
X464173Y154725D03*
X471260Y150000D03*
X421653Y168898D03*
X428740Y164173D03*
X435827Y168898D03*
X442913Y164173D03*
X450000Y168898D03*
X457086Y164173D03*
X464173Y168898D03*
X471260Y164173D03*
X535039Y126378D03*
Y183071D03*
Y140551D03*
Y154725D03*
X506693Y159055D03*
Y164567D03*
X535039Y168898D03*
X506693Y173229D03*
Y178740D03*
X513779Y174016D03*
X549212Y126378D03*
X542126Y121654D03*
X556299D03*
X549212Y183071D03*
X542126Y135827D03*
X549212Y140551D03*
X556299Y135827D03*
X542126Y150000D03*
X549212Y154725D03*
X556299Y150000D03*
X542126Y164173D03*
X549212Y168898D03*
X556299Y164173D03*
X730709Y221654D03*
X733858D03*
X724410D03*
Y234252D03*
Y240551D03*
Y246850D03*
Y253150D03*
Y227953D03*
Y265748D03*
Y259449D03*
X733857Y290944D03*
X727558D03*
X724410Y272047D03*
Y278346D03*
Y284645D03*
X765355Y240552D03*
X743307Y246850D03*
X762217Y240526D03*
X755880Y240563D03*
X749580D03*
X755869Y253149D03*
X762167Y246850D03*
X755907Y246851D03*
X749569Y246850D03*
X762168Y253149D03*
X749608Y253150D03*
X743282Y253161D03*
X755868Y265748D03*
X755882Y259461D03*
X762218Y259425D03*
X749582Y259461D03*
X743282D03*
X762181Y265762D03*
X749582Y265761D03*
X743282D03*
X743281Y240562D03*
X768480Y265762D03*
X768518Y259425D03*
X768467Y253149D03*
Y246850D03*
X762205Y221654D03*
X784252D03*
X777953D03*
X790551D03*
X740158D03*
X755906D03*
X746457D03*
X796850D03*
X743283Y272060D03*
X755882D03*
X749581D03*
X746456Y290944D03*
X740157D03*
%LPC*%
G75*
G54D40*
G01X13215Y-125739D02*
X14089Y-124864D01*
X14744Y-123406D01*
X15181Y-121363D01*
X14744Y-119614D01*
X13871Y-118447D01*
X12342Y-117572D01*
X6447D01*
Y-135072D01*
X13652D01*
X15181Y-133906D01*
X16054Y-132155D01*
X16491Y-130114D01*
X16054Y-128072D01*
X14744Y-126322D01*
X13215Y-125739D01*
X6447D01*
G01X25912Y-135072D02*
Y-123406D01*
G01Y-125739D02*
X27004Y-124572D01*
X28096Y-123697D01*
X29624Y-123406D01*
X30715Y-123697D01*
X32026Y-124572D01*
G01X41884Y-140322D02*
X43194Y-140905D01*
X44941Y-140322D01*
X46032Y-139156D01*
X46906Y-137697D01*
X48215Y-133031D01*
X51054Y-123406D01*
G01X44067D02*
X48215Y-133031D01*
G01X67462Y-124864D02*
X65934Y-123697D01*
X64624Y-123406D01*
X62877Y-123989D01*
X61567Y-125155D01*
X60694Y-127197D01*
X60475Y-129239D01*
X60694Y-131281D01*
X61567Y-133031D01*
X62877Y-134489D01*
X64624Y-135072D01*
X66152Y-134489D01*
X67462Y-133322D01*
G01X78194Y-127197D02*
X85181D01*
X84526Y-125155D01*
X83434Y-123989D01*
X81906Y-123406D01*
X80377Y-123697D01*
X79067Y-124572D01*
X78194Y-126614D01*
X77757Y-128364D01*
Y-130114D01*
X78194Y-131864D01*
X79286Y-133614D01*
X80596Y-134780D01*
X82124Y-135072D01*
X83652Y-134489D01*
X85181Y-132739D01*
G01X121272Y-119031D02*
X119962Y-118155D01*
X118434Y-117572D01*
X116687D01*
X114722Y-118447D01*
X113194Y-119905D01*
X112102Y-121656D01*
X111229Y-124572D01*
X111010Y-127197D01*
X111447Y-129822D01*
X112102Y-131572D01*
X113412Y-133322D01*
X114941Y-134489D01*
X116469Y-135072D01*
X117997D01*
X119526Y-134489D01*
X120836Y-133614D01*
X121928Y-132448D01*
G01X137899Y-135072D02*
Y-123406D01*
G01Y-125447D02*
X137026Y-124281D01*
X135715Y-123697D01*
X134187Y-123406D01*
X132659Y-123989D01*
X131349Y-125155D01*
X130475Y-126905D01*
X130039Y-129239D01*
X130475Y-131572D01*
X131349Y-133322D01*
X132659Y-134489D01*
X134187Y-135072D01*
X135715Y-134780D01*
X137026Y-133906D01*
X137899Y-132739D01*
G01X147757Y-135072D02*
Y-123406D01*
G01Y-126322D02*
X148631Y-124864D01*
X149941Y-123697D01*
X151687Y-123406D01*
X153215Y-123697D01*
X154526Y-124864D01*
X155181Y-126905D01*
Y-135072D01*
G01X164384Y-140322D02*
X165694Y-140905D01*
X167441Y-140322D01*
X168532Y-139156D01*
X169406Y-137697D01*
X170715Y-133031D01*
X173554Y-123406D01*
G01X166567D02*
X170715Y-133031D01*
G01X186469Y-135072D02*
X185159Y-134780D01*
X183849Y-133614D01*
X182975Y-131572D01*
X182539Y-129239D01*
X182975Y-126905D01*
X183849Y-124864D01*
X185159Y-123697D01*
X186469Y-123406D01*
X187779Y-123697D01*
X189089Y-124864D01*
X189962Y-126905D01*
X190181Y-129239D01*
X189962Y-131572D01*
X189089Y-133614D01*
X187779Y-134780D01*
X186469Y-135072D01*
G01X200257D02*
Y-123406D01*
G01Y-126322D02*
X201131Y-124864D01*
X202441Y-123697D01*
X204187Y-123406D01*
X205715Y-123697D01*
X207026Y-124864D01*
X207681Y-126905D01*
Y-135072D01*
G01X236349Y-117572D02*
X241589D01*
G01X238969D02*
Y-135072D01*
G01X236349D02*
X241589D01*
G01X256469D02*
X254722Y-134780D01*
X253194Y-133614D01*
X251884Y-131864D01*
X251010Y-129822D01*
X250574Y-127489D01*
Y-125155D01*
X251010Y-122822D01*
X251884Y-120780D01*
X253194Y-119031D01*
X254722Y-117864D01*
X256469Y-117572D01*
X258215Y-117864D01*
X259744Y-119031D01*
X261054Y-120780D01*
X261928Y-122822D01*
X262364Y-125155D01*
Y-127489D01*
X261928Y-129822D01*
X261054Y-131864D01*
X259744Y-133614D01*
X258215Y-134780D01*
X256469Y-135072D01*
G01X268292D02*
Y-117572D01*
X273969Y-132155D01*
X279646Y-117572D01*
Y-135072D01*
G01X307877Y-140905D02*
X305694Y-137989D01*
X304602Y-135072D01*
Y-123406D01*
X305694Y-120489D01*
X307877Y-117572D01*
G01X321010Y-123406D02*
X323631Y-135072D01*
X326469Y-123406D01*
X329307Y-135072D01*
X331928Y-123406D01*
G01X340039Y-135655D02*
X347899Y-117572D01*
G01X376349D02*
X381589D01*
G01X378969D02*
Y-135072D01*
G01X376349D02*
X381589D01*
G01X396469D02*
X394722Y-134780D01*
X393194Y-133614D01*
X391884Y-131864D01*
X391010Y-129822D01*
X390574Y-127489D01*
Y-125155D01*
X391010Y-122822D01*
X391884Y-120780D01*
X393194Y-119031D01*
X394722Y-117864D01*
X396469Y-117572D01*
X398215Y-117864D01*
X399744Y-119031D01*
X401054Y-120780D01*
X401928Y-122822D01*
X402364Y-125155D01*
Y-127489D01*
X401928Y-129822D01*
X401054Y-131864D01*
X399744Y-133614D01*
X398215Y-134780D01*
X396469Y-135072D01*
G01X418772Y-119031D02*
X417462Y-118155D01*
X415934Y-117572D01*
X414187D01*
X412222Y-118447D01*
X410694Y-119905D01*
X409602Y-121656D01*
X408729Y-124572D01*
X408510Y-127197D01*
X408947Y-129822D01*
X409602Y-131572D01*
X410912Y-133322D01*
X412441Y-134489D01*
X413969Y-135072D01*
X415497D01*
X417026Y-134489D01*
X418336Y-133614D01*
X419428Y-132448D01*
G01X432561Y-140905D02*
X434744Y-137989D01*
X435836Y-135072D01*
Y-123406D01*
X434744Y-120489D01*
X432561Y-117572D01*
G01X180792Y-90072D02*
Y-72572D01*
X186469Y-87155D01*
X192146Y-72572D01*
Y-90072D01*
G01X203969D02*
X202659Y-89780D01*
X201349Y-88614D01*
X200475Y-86572D01*
X200039Y-84239D01*
X200475Y-81905D01*
X201349Y-79864D01*
X202659Y-78697D01*
X203969Y-78406D01*
X205279Y-78697D01*
X206589Y-79864D01*
X207462Y-81905D01*
X207681Y-84239D01*
X207462Y-86572D01*
X206589Y-88614D01*
X205279Y-89780D01*
X203969Y-90072D01*
G01X225399Y-72572D02*
Y-90072D01*
G01Y-87448D02*
X224526Y-88906D01*
X223215Y-89780D01*
X221687Y-90072D01*
X219941Y-89489D01*
X218631Y-88031D01*
X217757Y-86281D01*
X217539Y-84239D01*
X217757Y-82197D01*
X218631Y-80447D01*
X219941Y-78989D01*
X221687Y-78406D01*
X223215Y-78697D01*
X224307Y-79281D01*
X225399Y-80447D01*
G01X235694Y-82197D02*
X242681D01*
X242026Y-80155D01*
X240934Y-78989D01*
X239406Y-78406D01*
X237877Y-78697D01*
X236567Y-79572D01*
X235694Y-81614D01*
X235257Y-83364D01*
Y-85114D01*
X235694Y-86864D01*
X236786Y-88614D01*
X238096Y-89780D01*
X239624Y-90072D01*
X241152Y-89489D01*
X242681Y-87739D01*
G01X256469Y-90072D02*
Y-72572D01*
G01X490269Y-135072D02*
Y-117572D01*
X487649Y-121072D01*
G01Y-135072D02*
X492889D01*
G01X503621Y-127781D02*
X505149Y-125739D01*
X506459Y-124572D01*
X508206Y-123989D01*
X509734Y-124572D01*
X510826Y-125739D01*
X511699Y-127489D01*
X511917Y-129530D01*
X511699Y-131281D01*
X510826Y-133031D01*
X509515Y-134489D01*
X507987Y-135072D01*
X506241Y-134489D01*
X504712Y-132739D01*
X503839Y-130114D01*
X503621Y-127197D01*
X504057Y-123406D01*
X504712Y-121363D01*
X505804Y-119322D01*
X507332Y-117864D01*
X508861Y-117572D01*
X510389Y-118155D01*
X511481Y-119614D01*
G01X520466Y-131572D02*
X521775Y-133614D01*
X523522Y-134780D01*
X525487Y-135072D01*
X527234Y-134780D01*
X528981Y-133322D01*
X530072Y-131572D01*
X530291Y-129822D01*
X529854Y-127781D01*
X528326Y-126322D01*
X526797Y-125739D01*
X524832D01*
G01X526797D02*
X528107Y-124864D01*
X529199Y-123406D01*
X529636Y-121656D01*
X529199Y-119905D01*
X528107Y-118447D01*
X526142Y-117572D01*
X524177Y-117864D01*
X522212Y-119031D01*
G01X542769Y-135072D02*
Y-117572D01*
X540149Y-121072D01*
G01Y-135072D02*
X545389D01*
G01X560269D02*
X561797Y-134780D01*
X563544Y-133906D01*
X564636Y-132448D01*
X565072Y-130405D01*
X564636Y-128364D01*
X563326Y-126614D01*
X561361Y-125739D01*
X559177D01*
X557867Y-125155D01*
X556775Y-123697D01*
X556339Y-121656D01*
X556994Y-119614D01*
X558522Y-118155D01*
X560269Y-117572D01*
X562015Y-118155D01*
X563544Y-119614D01*
X564199Y-121656D01*
X563762Y-123697D01*
X562671Y-125155D01*
X561361Y-125739D01*
X559177D01*
X557212Y-126614D01*
X555902Y-128364D01*
X555466Y-130405D01*
X555902Y-132448D01*
X556994Y-133906D01*
X558741Y-134780D01*
X560269Y-135072D01*
G01X477152Y-90072D02*
Y-72572D01*
X482392D01*
X484139Y-73447D01*
X485449Y-75489D01*
X485886Y-77822D01*
X485449Y-80155D01*
X484357Y-81905D01*
X482392Y-82781D01*
X477152D01*
G01X503822Y-74031D02*
X502512Y-73155D01*
X500984Y-72572D01*
X499237D01*
X497272Y-73447D01*
X495744Y-74905D01*
X494652Y-76656D01*
X493779Y-79572D01*
X493560Y-82197D01*
X493997Y-84822D01*
X494652Y-86572D01*
X495962Y-88322D01*
X497491Y-89489D01*
X499019Y-90072D01*
X500547D01*
X502076Y-89489D01*
X503386Y-88614D01*
X504478Y-87448D01*
G01X518265Y-80739D02*
X519139Y-79864D01*
X519794Y-78406D01*
X520231Y-76363D01*
X519794Y-74614D01*
X518921Y-73447D01*
X517392Y-72572D01*
X511497D01*
Y-90072D01*
X518702D01*
X520231Y-88906D01*
X521104Y-87155D01*
X521541Y-85114D01*
X521104Y-83072D01*
X519794Y-81322D01*
X518265Y-80739D01*
X511497D01*
G01X527469Y-95905D02*
X540569D01*
G01X546497Y-90072D02*
Y-72572D01*
X556541Y-90072D01*
Y-72572D01*
G01X569019Y-90072D02*
X567272Y-89780D01*
X565744Y-88614D01*
X564434Y-86864D01*
X563560Y-84822D01*
X563124Y-82489D01*
Y-80155D01*
X563560Y-77822D01*
X564434Y-75780D01*
X565744Y-74031D01*
X567272Y-72864D01*
X569019Y-72572D01*
X570765Y-72864D01*
X572294Y-74031D01*
X573604Y-75780D01*
X574478Y-77822D01*
X574914Y-80155D01*
Y-82489D01*
X574478Y-84822D01*
X573604Y-86864D01*
X572294Y-88614D01*
X570765Y-89780D01*
X569019Y-90072D01*
G01X647421Y-120489D02*
X648731Y-118739D01*
X650259Y-117864D01*
X652006Y-117572D01*
X654189Y-118155D01*
X655717Y-119614D01*
X656154Y-121363D01*
X655936Y-123114D01*
X655062Y-124572D01*
X650696Y-127489D01*
X648731Y-129530D01*
X647421Y-132448D01*
X646984Y-135072D01*
X656154D01*
G01X619860Y-72572D02*
X625319Y-90072D01*
X630778Y-72572D01*
G01X647186Y-90072D02*
X638452D01*
Y-72572D01*
X647186D01*
G01X643692Y-81030D02*
X638452D01*
G01X655952Y-90072D02*
Y-72572D01*
X661411D01*
X663157Y-73447D01*
X664249Y-74614D01*
X664686Y-76947D01*
X664249Y-79281D01*
X662939Y-80739D01*
X661411Y-81614D01*
X655952D01*
G01X661411D02*
X664686Y-90072D01*
G01X677819Y-90655D02*
X677382Y-90364D01*
Y-89780D01*
X677819Y-89489D01*
X678256Y-89780D01*
Y-90364D01*
X677819Y-90655D01*
G01X753402Y-117572D02*
Y-135072D01*
X762136D01*
G01X777889D02*
Y-117572D01*
X769810Y-130114D01*
X780728D01*
G01X787310Y-117572D02*
X792769Y-135072D01*
X798228Y-117572D01*
G01X815072Y-119031D02*
X813762Y-118155D01*
X812234Y-117572D01*
X810487D01*
X808522Y-118447D01*
X806994Y-119905D01*
X805902Y-121656D01*
X805029Y-124572D01*
X804810Y-127197D01*
X805247Y-129822D01*
X805902Y-131572D01*
X807212Y-133322D01*
X808741Y-134489D01*
X810269Y-135072D01*
X811797D01*
X813326Y-134489D01*
X814636Y-133614D01*
X815728Y-132448D01*
G01X832572Y-119031D02*
X831262Y-118155D01*
X829734Y-117572D01*
X827987D01*
X826022Y-118447D01*
X824494Y-119905D01*
X823402Y-121656D01*
X822529Y-124572D01*
X822310Y-127197D01*
X822747Y-129822D01*
X823402Y-131572D01*
X824712Y-133322D01*
X826241Y-134489D01*
X827769Y-135072D01*
X829297D01*
X830826Y-134489D01*
X832136Y-133614D01*
X833228Y-132448D01*
G01X753402Y-72572D02*
Y-90072D01*
X762136D01*
G01X779199D02*
Y-78406D01*
G01Y-80447D02*
X778326Y-79281D01*
X777015Y-78697D01*
X775487Y-78406D01*
X773959Y-78989D01*
X772649Y-80155D01*
X771775Y-81905D01*
X771339Y-84239D01*
X771775Y-86572D01*
X772649Y-88322D01*
X773959Y-89489D01*
X775487Y-90072D01*
X777015Y-89780D01*
X778326Y-88906D01*
X779199Y-87739D01*
G01X788184Y-95322D02*
X789494Y-95905D01*
X791241Y-95322D01*
X792332Y-94156D01*
X793206Y-92697D01*
X794515Y-88031D01*
X797354Y-78406D01*
G01X790367D02*
X794515Y-88031D01*
G01X806994Y-82197D02*
X813981D01*
X813326Y-80155D01*
X812234Y-78989D01*
X810706Y-78406D01*
X809177Y-78697D01*
X807867Y-79572D01*
X806994Y-81614D01*
X806557Y-83364D01*
Y-85114D01*
X806994Y-86864D01*
X808086Y-88614D01*
X809396Y-89780D01*
X810924Y-90072D01*
X812452Y-89489D01*
X813981Y-87739D01*
G01X824712Y-90072D02*
Y-78406D01*
G01Y-80739D02*
X825804Y-79572D01*
X826896Y-78697D01*
X828424Y-78406D01*
X829515Y-78697D01*
X830826Y-79572D01*
G01X917819Y-135072D02*
X916072Y-134780D01*
X914544Y-133614D01*
X913234Y-131864D01*
X912360Y-129822D01*
X911924Y-127489D01*
Y-125155D01*
X912360Y-122822D01*
X913234Y-120780D01*
X914544Y-119031D01*
X916072Y-117864D01*
X917819Y-117572D01*
X919565Y-117864D01*
X921094Y-119031D01*
X922404Y-120780D01*
X923278Y-122822D01*
X923714Y-125155D01*
Y-127489D01*
X923278Y-129822D01*
X922404Y-131864D01*
X921094Y-133614D01*
X919565Y-134780D01*
X917819Y-135072D01*
G01X919565Y-130405D02*
X922186Y-135072D01*
G01X930516Y-117572D02*
Y-130114D01*
X931389Y-132739D01*
X933136Y-134489D01*
X935319Y-135072D01*
X937502Y-134489D01*
X939249Y-132739D01*
X940122Y-130114D01*
Y-117572D01*
G01X950199D02*
X955439D01*
G01X952819D02*
Y-135072D01*
G01X950199D02*
X955439D01*
G01X965297D02*
Y-117572D01*
X975341Y-135072D01*
Y-117572D01*
G01X992622Y-119031D02*
X991312Y-118155D01*
X989784Y-117572D01*
X988037D01*
X986072Y-118447D01*
X984544Y-119905D01*
X983452Y-121656D01*
X982579Y-124572D01*
X982360Y-127197D01*
X982797Y-129822D01*
X983452Y-131572D01*
X984762Y-133322D01*
X986291Y-134489D01*
X987819Y-135072D01*
X989347D01*
X990876Y-134489D01*
X992186Y-133614D01*
X993278Y-132448D01*
G01X1005319Y-135072D02*
Y-127197D01*
X1000952Y-117572D01*
G01X1009686D02*
X1005319Y-127197D01*
G01X895516Y-90072D02*
Y-72572D01*
X899882D01*
X901629Y-73447D01*
X902939Y-74614D01*
X904031Y-76363D01*
X904904Y-78406D01*
X905122Y-81322D01*
X904904Y-84239D01*
X904031Y-86281D01*
X902939Y-88031D01*
X901629Y-89197D01*
X899882Y-90072D01*
X895516D01*
G01X914544Y-82197D02*
X921531D01*
X920876Y-80155D01*
X919784Y-78989D01*
X918256Y-78406D01*
X916727Y-78697D01*
X915417Y-79572D01*
X914544Y-81614D01*
X914107Y-83364D01*
Y-85114D01*
X914544Y-86864D01*
X915636Y-88614D01*
X916946Y-89780D01*
X918474Y-90072D01*
X920002Y-89489D01*
X921531Y-87739D01*
G01X932044Y-88031D02*
X933136Y-89197D01*
X934664Y-90072D01*
X935974D01*
X937284Y-89489D01*
X938157Y-88614D01*
X938594Y-87448D01*
X938376Y-85697D01*
X937502Y-84822D01*
X933572Y-83072D01*
X932699Y-81030D01*
X933136Y-79572D01*
X934009Y-78697D01*
X935319Y-78406D01*
X936629Y-78697D01*
X937939Y-79572D01*
G01X952819Y-78406D02*
Y-90072D01*
G01Y-73739D02*
X952382Y-73447D01*
Y-72864D01*
X952819Y-72572D01*
X953256Y-72864D01*
Y-73447D01*
X952819Y-73739D01*
G01X967262Y-94447D02*
X968791Y-95614D01*
X970537Y-95905D01*
X972065Y-95614D01*
X973376Y-94156D01*
X974249Y-92114D01*
Y-78406D01*
G01Y-80739D02*
X973376Y-79572D01*
X972065Y-78697D01*
X970537Y-78406D01*
X968791Y-78989D01*
X967699Y-80155D01*
X966825Y-82197D01*
X966389Y-84239D01*
X966607Y-85989D01*
X967481Y-88031D01*
X968791Y-89489D01*
X970537Y-90072D01*
X971847Y-89780D01*
X973376Y-88614D01*
X974249Y-87448D01*
G01X984107Y-90072D02*
Y-78406D01*
G01Y-81322D02*
X984981Y-79864D01*
X986291Y-78697D01*
X988037Y-78406D01*
X989565Y-78697D01*
X990876Y-79864D01*
X991531Y-81905D01*
Y-90072D01*
G01X1002044Y-82197D02*
X1009031D01*
X1008376Y-80155D01*
X1007284Y-78989D01*
X1005756Y-78406D01*
X1004227Y-78697D01*
X1002917Y-79572D01*
X1002044Y-81614D01*
X1001607Y-83364D01*
Y-85114D01*
X1002044Y-86864D01*
X1003136Y-88614D01*
X1004446Y-89780D01*
X1005974Y-90072D01*
X1007502Y-89489D01*
X1009031Y-87739D01*
G01X1019762Y-90072D02*
Y-78406D01*
G01Y-80739D02*
X1020854Y-79572D01*
X1021946Y-78697D01*
X1023474Y-78406D01*
X1024565Y-78697D01*
X1025876Y-79572D01*
G01X1066519Y-117572D02*
X1064772Y-118155D01*
X1063462Y-119614D01*
X1062589Y-121363D01*
X1061934Y-123697D01*
X1061716Y-126322D01*
X1061934Y-128947D01*
X1062589Y-131281D01*
X1063462Y-133031D01*
X1064772Y-134489D01*
X1066519Y-135072D01*
X1068265Y-134489D01*
X1069576Y-133031D01*
X1070449Y-131281D01*
X1071104Y-128947D01*
X1071322Y-126322D01*
X1071104Y-123697D01*
X1070449Y-121363D01*
X1069576Y-119614D01*
X1068265Y-118155D01*
X1066519Y-117572D01*
G01X1084019Y-135072D02*
X1085547Y-134780D01*
X1087294Y-133906D01*
X1088386Y-132448D01*
X1088822Y-130405D01*
X1088386Y-128364D01*
X1087076Y-126614D01*
X1085111Y-125739D01*
X1082927D01*
X1081617Y-125155D01*
X1080525Y-123697D01*
X1080089Y-121656D01*
X1080744Y-119614D01*
X1082272Y-118155D01*
X1084019Y-117572D01*
X1085765Y-118155D01*
X1087294Y-119614D01*
X1087949Y-121656D01*
X1087512Y-123697D01*
X1086421Y-125155D01*
X1085111Y-125739D01*
X1082927D01*
X1080962Y-126614D01*
X1079652Y-128364D01*
X1079216Y-130405D01*
X1079652Y-132448D01*
X1080744Y-133906D01*
X1082491Y-134780D01*
X1084019Y-135072D01*
G01X1097589Y-135655D02*
X1105449Y-117572D01*
G01X1119019D02*
X1117272Y-118155D01*
X1115962Y-119614D01*
X1115089Y-121363D01*
X1114434Y-123697D01*
X1114216Y-126322D01*
X1114434Y-128947D01*
X1115089Y-131281D01*
X1115962Y-133031D01*
X1117272Y-134489D01*
X1119019Y-135072D01*
X1120765Y-134489D01*
X1122076Y-133031D01*
X1122949Y-131281D01*
X1123604Y-128947D01*
X1123822Y-126322D01*
X1123604Y-123697D01*
X1122949Y-121363D01*
X1122076Y-119614D01*
X1120765Y-118155D01*
X1119019Y-117572D01*
G01X1136082Y-135072D02*
X1136519Y-131281D01*
X1137174Y-128072D01*
X1138047Y-125155D01*
X1139139Y-121947D01*
X1140886Y-117572D01*
X1132152D01*
G01X1150089Y-135655D02*
X1157949Y-117572D01*
G01X1167371Y-120489D02*
X1168681Y-118739D01*
X1170209Y-117864D01*
X1171956Y-117572D01*
X1174139Y-118155D01*
X1175667Y-119614D01*
X1176104Y-121363D01*
X1175886Y-123114D01*
X1175012Y-124572D01*
X1170646Y-127489D01*
X1168681Y-129530D01*
X1167371Y-132448D01*
X1166934Y-135072D01*
X1176104D01*
G01X1189019Y-117572D02*
X1187272Y-118155D01*
X1185962Y-119614D01*
X1185089Y-121363D01*
X1184434Y-123697D01*
X1184216Y-126322D01*
X1184434Y-128947D01*
X1185089Y-131281D01*
X1185962Y-133031D01*
X1187272Y-134489D01*
X1189019Y-135072D01*
X1190765Y-134489D01*
X1192076Y-133031D01*
X1192949Y-131281D01*
X1193604Y-128947D01*
X1193822Y-126322D01*
X1193604Y-123697D01*
X1192949Y-121363D01*
X1192076Y-119614D01*
X1190765Y-118155D01*
X1189019Y-117572D01*
G01X1206519Y-135072D02*
Y-117572D01*
X1203899Y-121072D01*
G01Y-135072D02*
X1209139D01*
G01X1223582D02*
X1224019Y-131281D01*
X1224674Y-128072D01*
X1225547Y-125155D01*
X1226639Y-121947D01*
X1228386Y-117572D01*
X1219652D01*
G01X1114216Y-90072D02*
Y-72572D01*
X1118582D01*
X1120329Y-73447D01*
X1121639Y-74614D01*
X1122731Y-76363D01*
X1123604Y-78406D01*
X1123822Y-81322D01*
X1123604Y-84239D01*
X1122731Y-86281D01*
X1121639Y-88031D01*
X1120329Y-89197D01*
X1118582Y-90072D01*
X1114216D01*
G01X1140449D02*
Y-78406D01*
G01Y-80447D02*
X1139576Y-79281D01*
X1138265Y-78697D01*
X1136737Y-78406D01*
X1135209Y-78989D01*
X1133899Y-80155D01*
X1133025Y-81905D01*
X1132589Y-84239D01*
X1133025Y-86572D01*
X1133899Y-88322D01*
X1135209Y-89489D01*
X1136737Y-90072D01*
X1138265Y-89780D01*
X1139576Y-88906D01*
X1140449Y-87739D01*
G01X1154019Y-72572D02*
Y-90072D01*
G01X1150962Y-78406D02*
X1157076D01*
G01X1168244Y-82197D02*
X1175231D01*
X1174576Y-80155D01*
X1173484Y-78989D01*
X1171956Y-78406D01*
X1170427Y-78697D01*
X1169117Y-79572D01*
X1168244Y-81614D01*
X1167807Y-83364D01*
Y-85114D01*
X1168244Y-86864D01*
X1169336Y-88614D01*
X1170646Y-89780D01*
X1172174Y-90072D01*
X1173702Y-89489D01*
X1175231Y-87739D01*
G54D39*
G01X-13131Y-65072D02*
Y-145072D01*
G01D02*
X1244069D01*
G01X-29131Y-65072D02*
Y-33072D01*
G01X-13131Y-65072D02*
X1244069D01*
G01X-13131Y-100572D02*
X1244069D01*
G01X-17131Y-49072D02*
G02I-12000J0D01*
G01X-22281D02*
G02I-6850J0D01*
G01X-13131D02*
X-45131D01*
G01X456569Y-65072D02*
Y-145072D01*
G01X594069Y-65072D02*
Y-145072D01*
G01X709069Y-65072D02*
Y-145072D01*
G01X876569Y-65072D02*
Y-145072D01*
G01X1046569Y-65072D02*
Y-145072D01*
G01X1244069Y-65072D02*
Y-145072D01*
G01X1272069Y-49072D02*
G02I-12000J0D01*
G01X1266919D02*
G02I-6850J0D01*
G01X1276069D02*
X1244069D01*
G01X1260069Y-65072D02*
Y-33072D01*
M02*
